FILE_TYPE = MACRO_DRAWING;
SET COLOR_WIRE YELLOW;
SET COLOR_PROP MONO;
SET COLOR_DOT WHITE;
SET COLOR_ARC YELLOW;
SET COLOR_BODY GREEN;
SET COLOR_NOTE MONO;
SET PROP_DISPLAY VALUE;
SET PAGE_NUMBER P101;
FORCEADD VCC_CORE..1
(-3850 4350);
FORCEPROP 3 LASTPIN (-3850 4300) SIG_NAME P3V3_STBY_MNG\g
J 0
(-3840 4310);
DISPLAY 0.659574 (-3840 4310);
PAINT MONO (-3840 4310);
DISPLAY INVISIBLE (-3840 4310);
FORCEPROP 1 LAST HDL_POWER P3V3_STBY_MNG
J 1
(-3800 4400);
DISPLAY 0.617021 (-3800 4400);
PAINT GREEN (-3800 4400);
FORCEPROP 1 LAST PATH I100
J 0
(-3800 4375);
DISPLAY 0.872340 (-3800 4375);
PAINT AQUA (-3800 4375);
DISPLAY INVISIBLE (-3800 4375);
FORCEPROP 2 LAST CDS_LIB mstr_symbols
J 0
(-3850 4350);
PAINT ORANGE (-3850 4350);
DISPLAY INVISIBLE (-3850 4350);
FORCEPROP 0 LAST VOLTAGE 5
J 0
(-3850 4350);
PAINT SKYBLUE (-3850 4350);
DISPLAY INVISIBLE (-3850 4350);
FORCEADD VCC_CORE..1
(-2975 4275);
FORCEPROP 3 LASTPIN (-2975 4225) SIG_NAME P3V3_STBY_MNG_RGMII\g
J 0
(-2965 4235);
DISPLAY 0.659574 (-2965 4235);
PAINT MONO (-2965 4235);
DISPLAY INVISIBLE (-2965 4235);
FORCEPROP 1 LAST HDL_POWER P3V3_STBY_MNG_RGMII
J 1
(-2925 4325);
DISPLAY 0.617021 (-2925 4325);
PAINT GREEN (-2925 4325);
FORCEPROP 1 LAST PATH I101
J 0
(-2925 4300);
DISPLAY 0.872340 (-2925 4300);
PAINT AQUA (-2925 4300);
DISPLAY INVISIBLE (-2925 4300);
FORCEPROP 2 LAST CDS_LIB mstr_symbols
J 0
(-2975 4275);
PAINT ORANGE (-2975 4275);
DISPLAY INVISIBLE (-2975 4275);
FORCEPROP 0 LAST VOLTAGE 3.3
J 0
(-2975 4275);
PAINT SKYBLUE (-2975 4275);
DISPLAY INVISIBLE (-2975 4275);
FORCEADD VCC_CORE..1
(-2425 4375);
FORCEPROP 3 LASTPIN (-2425 4325) SIG_NAME P3V3_STBY_MNG\g
J 0
(-2415 4335);
DISPLAY 0.659574 (-2415 4335);
PAINT MONO (-2415 4335);
DISPLAY INVISIBLE (-2415 4335);
FORCEPROP 1 LAST HDL_POWER P3V3_STBY_MNG
J 1
(-2375 4425);
DISPLAY 0.617021 (-2375 4425);
PAINT GREEN (-2375 4425);
FORCEPROP 1 LAST PATH I102
J 0
(-2375 4400);
DISPLAY 0.872340 (-2375 4400);
PAINT AQUA (-2375 4400);
DISPLAY INVISIBLE (-2375 4400);
FORCEPROP 2 LAST CDS_LIB mstr_symbols
J 0
(-2425 4375);
PAINT ORANGE (-2425 4375);
DISPLAY INVISIBLE (-2425 4375);
FORCEPROP 0 LAST VOLTAGE 5
J 0
(-2425 4375);
PAINT SKYBLUE (-2425 4375);
DISPLAY INVISIBLE (-2425 4375);
FORCEADD VCC_CORE..1
(-1675 4325);
FORCEPROP 3 LASTPIN (-1675 4275) SIG_NAME P3V3_STBY_MNG_RMII\g
J 0
(-1665 4285);
DISPLAY 0.659574 (-1665 4285);
PAINT MONO (-1665 4285);
DISPLAY INVISIBLE (-1665 4285);
FORCEPROP 1 LAST HDL_POWER P3V3_STBY_MNG_RMII
J 1
(-1625 4375);
DISPLAY 0.617021 (-1625 4375);
PAINT GREEN (-1625 4375);
FORCEPROP 1 LAST PATH I103
J 0
(-1625 4350);
DISPLAY 0.872340 (-1625 4350);
PAINT AQUA (-1625 4350);
DISPLAY INVISIBLE (-1625 4350);
FORCEPROP 2 LAST CDS_LIB mstr_symbols
J 0
(-1675 4325);
PAINT ORANGE (-1675 4325);
DISPLAY INVISIBLE (-1675 4325);
FORCEPROP 0 LAST VOLTAGE 3.3
J 0
(-1675 4325);
PAINT SKYBLUE (-1675 4325);
DISPLAY INVISIBLE (-1675 4325);
FORCEADD CAP_A..1
(-4875 4000);
FORCEPROP 1 LASTPIN (-4875 3900) $PN 2
J 0
(-4865 3880);
DISPLAY 0.617021 (-4865 3880);
PAINT WHITE (-4865 3880);
FORCEPROP 1 LASTPIN (-4875 4100) $PN 1
J 0
(-4865 4080);
DISPLAY 0.617021 (-4865 4080);
PAINT WHITE (-4865 4080);
FORCEPROP 1 LAST MATERIAL X7R
J 0
(-4825 3900);
DISPLAY 0.617021 (-4825 3900);
PAINT SKYBLUE (-4825 3900);
FORCEPROP 1 LAST VOLTAGE 25V
J 0
(-4825 4000);
DISPLAY 0.617021 (-4825 4000);
PAINT SKYBLUE (-4825 4000);
FORCEPROP 1 LAST PACK_TYPE 0402V
J 0
(-4825 3800);
DISPLAY 0.617021 (-4825 3800);
PAINT SKYBLUE (-4825 3800);
FORCEPROP 1 LAST TOLERANCE 10%
J 0
(-4825 3950);
DISPLAY 0.617021 (-4825 3950);
PAINT SKYBLUE (-4825 3950);
FORCEPROP 1 LAST VALUE 0.01UF
J 0
(-4825 4050);
DISPLAY 0.617021 (-4825 4050);
PAINT SKYBLUE (-4825 4050);
FORCEPROP 1 LAST PART_NUMBER A36096-045
J 0
(-4825 3850);
DISPLAY 0.617021 (-4825 3850);
PAINT BLUE (-4825 3850);
FORCEPROP 1 LAST LOCATION C2T18
J 0
(-4825 4100);
DISPLAY 0.617021 (-4825 4100);
PAINT AQUA (-4825 4100);
FORCEPROP 2 LAST ROOM SYS_CLOCK
J 0
(-4825 4150);
DISPLAY 1.127660 (-4825 4150);
PAINT WHITE (-4825 4150);
DISPLAY INVISIBLE (-4825 4150);
FORCEPROP 1 LAST PATH I104
J 0
(-4825 4150);
DISPLAY 0.978723 (-4825 4150);
PAINT WHITE (-4825 4150);
DISPLAY INVISIBLE (-4825 4150);
FORCEPROP 2 LAST $SEC 1
J 0
(-4825 4200);
DISPLAY 1.510638 (-4825 4200);
PAINT MONO (-4825 4200);
DISPLAY INVISIBLE (-4825 4200);
FORCEPROP 2 LAST CDS_SEC 1
J 0
(-4825 4200);
DISPLAY 2.276596 (-4825 4200);
PAINT ORANGE (-4825 4200);
DISPLAY INVISIBLE (-4825 4200);
FORCEPROP 2 LAST CDS_LIB dev_discrete
J 0
(-4875 4000);
PAINT ORANGE (-4875 4000);
DISPLAY INVISIBLE (-4875 4000);
FORCEPROP 2 LAST BOM_COST SM_CONTROLLER
J 0
(-4825 4125);
DISPLAY 1.617021 (-4825 4125);
PAINT WHITE (-4825 4125);
DISPLAY INVISIBLE (-4825 4125);
FORCEPROP 2 LAST CDS_LOCATION C2T18
J 0
(-4825 4100);
DISPLAY 0.617021 (-4825 4100);
PAINT AQUA (-4825 4100);
DISPLAY INVISIBLE (-4825 4100);
FORCEADD RES..1
(-5150 4175);
FORCEPROP 1 LASTPIN (-5250 4175) $PN 1
J 0
(-5238 4187);
DISPLAY 0.617021 (-5238 4187);
PAINT ORANGE (-5238 4187);
FORCEPROP 1 LASTPIN (-5050 4175) $PN 2
J 0
(-5088 4187);
DISPLAY 0.617021 (-5088 4187);
PAINT ORANGE (-5088 4187);
FORCEPROP 1 LAST WATTAGE 1/10W
J 2
(-5175 4025);
DISPLAY 0.617021 (-5175 4025);
PAINT SKYBLUE (-5175 4025);
FORCEPROP 1 LAST MATERIAL CHIP
J 0
(-5150 4025);
DISPLAY 0.617021 (-5150 4025);
PAINT SKYBLUE (-5150 4025);
FORCEPROP 1 LAST PACK_TYPE 0603
J 0
(-5025 4075);
DISPLAY 0.617021 (-5025 4075);
PAINT SKYBLUE (-5025 4075);
FORCEPROP 1 LAST TOLERANCE 1.0%
J 0
(-5150 4075);
DISPLAY 0.617021 (-5150 4075);
PAINT SKYBLUE (-5150 4075);
FORCEPROP 1 LAST VALUE 2.2
J 2
(-5175 4075);
DISPLAY 0.617021 (-5175 4075);
PAINT SKYBLUE (-5175 4075);
FORCEPROP 1 LAST PART_NUMBER G22026-127
J 0
(-5200 4275);
DISPLAY 0.617021 (-5200 4275);
PAINT BLUE (-5200 4275);
FORCEPROP 1 LAST LOCATION R2T21
J 0
(-5200 4225);
DISPLAY 0.617021 (-5200 4225);
PAINT AQUA (-5200 4225);
FORCEPROP 2 LAST ROOM SYS_CLOCK
J 0
(-5300 4325);
DISPLAY 1.127660 (-5300 4325);
PAINT WHITE (-5300 4325);
DISPLAY INVISIBLE (-5300 4325);
FORCEPROP 1 LAST PATH I105
J 0
(-5200 4325);
DISPLAY 0.978723 (-5200 4325);
PAINT WHITE (-5200 4325);
DISPLAY INVISIBLE (-5200 4325);
FORCEPROP 2 LAST CDS_LOCATION R2T21
J 0
(-5200 4225);
DISPLAY 0.617021 (-5200 4225);
PAINT AQUA (-5200 4225);
DISPLAY INVISIBLE (-5200 4225);
FORCEPROP 2 LAST SEC 1
J 0
(-5200 4375);
DISPLAY 0.680851 (-5200 4375);
PAINT MONO (-5200 4375);
DISPLAY INVISIBLE (-5200 4375);
FORCEPROP 2 LAST CDS_LIB mstr_discrete
J 0
(-5150 4175);
DISPLAY 2.127660 (-5150 4175);
PAINT ORANGE (-5150 4175);
DISPLAY INVISIBLE (-5150 4175);
FORCEPROP 2 LAST BOM_COST SM_CONTROLLER
J 0
(-5200 4250);
DISPLAY 1.617021 (-5200 4250);
PAINT WHITE (-5200 4250);
DISPLAY INVISIBLE (-5200 4250);
FORCEPROP 2 LAST SEC_TYPE 0603
J 0
(-5200 4375);
DISPLAY 1.021277 (-5200 4375);
PAINT ORANGE (-5200 4375);
DISPLAY INVISIBLE (-5200 4375);
FORCEADD CAP_A..1
(-4475 4000);
FORCEPROP 1 LASTPIN (-4475 3900) $PN 2
J 0
(-4465 3880);
DISPLAY 0.617021 (-4465 3880);
PAINT WHITE (-4465 3880);
FORCEPROP 1 LASTPIN (-4475 4100) $PN 1
J 0
(-4465 4080);
DISPLAY 0.617021 (-4465 4080);
PAINT WHITE (-4465 4080);
FORCEPROP 1 LAST MATERIAL X6S
J 0
(-4425 3900);
DISPLAY 0.617021 (-4425 3900);
PAINT SKYBLUE (-4425 3900);
FORCEPROP 1 LAST VOLTAGE 6.3V
J 0
(-4425 4000);
DISPLAY 0.617021 (-4425 4000);
PAINT SKYBLUE (-4425 4000);
FORCEPROP 1 LAST PACK_TYPE 0402V
J 0
(-4425 3800);
DISPLAY 0.617021 (-4425 3800);
PAINT SKYBLUE (-4425 3800);
FORCEPROP 1 LAST TOLERANCE 10%
J 0
(-4425 3950);
DISPLAY 0.617021 (-4425 3950);
PAINT SKYBLUE (-4425 3950);
FORCEPROP 1 LAST VALUE 1.0UF
J 0
(-4425 4050);
DISPLAY 0.617021 (-4425 4050);
PAINT SKYBLUE (-4425 4050);
FORCEPROP 1 LAST PART_NUMBER D97712-004
J 0
(-4425 3850);
DISPLAY 0.617021 (-4425 3850);
PAINT BLUE (-4425 3850);
FORCEPROP 1 LAST LOCATION C2T19
J 0
(-4425 4100);
DISPLAY 0.617021 (-4425 4100);
PAINT AQUA (-4425 4100);
FORCEPROP 2 LAST ROOM SYS_CLOCK
J 0
(-4425 4150);
DISPLAY 1.127660 (-4425 4150);
PAINT WHITE (-4425 4150);
DISPLAY INVISIBLE (-4425 4150);
FORCEPROP 1 LAST PATH I106
J 0
(-4425 4150);
DISPLAY 0.978723 (-4425 4150);
PAINT WHITE (-4425 4150);
DISPLAY INVISIBLE (-4425 4150);
FORCEPROP 2 LAST $SEC 1
J 0
(-4425 4200);
DISPLAY 1.510638 (-4425 4200);
PAINT MONO (-4425 4200);
DISPLAY INVISIBLE (-4425 4200);
FORCEPROP 2 LAST CDS_SEC 1
J 0
(-4425 4200);
DISPLAY 2.276596 (-4425 4200);
PAINT ORANGE (-4425 4200);
DISPLAY INVISIBLE (-4425 4200);
FORCEPROP 2 LAST CDS_LIB dev_discrete
J 0
(-4475 4000);
PAINT ORANGE (-4475 4000);
DISPLAY INVISIBLE (-4475 4000);
FORCEPROP 2 LAST BOM_COST SM_CONTROLLER
J 0
(-4425 4125);
DISPLAY 1.617021 (-4425 4125);
PAINT WHITE (-4425 4125);
DISPLAY INVISIBLE (-4425 4125);
FORCEPROP 2 LAST CDS_LOCATION C2T19
J 0
(-4425 4100);
DISPLAY 0.617021 (-4425 4100);
PAINT AQUA (-4425 4100);
DISPLAY INVISIBLE (-4425 4100);
FORCEADD GND..1
(-4475 3675);
FORCEPROP 3 LASTPIN (-4475 3725) SIG_NAME GND\g
J 0
(-4465 3735);
DISPLAY 0.659574 (-4465 3735);
PAINT MONO (-4465 3735);
DISPLAY INVISIBLE (-4465 3735);
FORCEPROP 1 LAST HDL_POWER GND
J 0
(-4475 3825);
PAINT GREEN (-4475 3825);
DISPLAY INVISIBLE (-4475 3825);
FORCEPROP 2 LAST ROOM SYS_CLOCK
J 0
(-4800 3750);
DISPLAY 1.127660 (-4800 3750);
PAINT WHITE (-4800 3750);
DISPLAY INVISIBLE (-4800 3750);
FORCEPROP 1 LAST PATH I107
J 0
(-4400 3675);
DISPLAY 0.872340 (-4400 3675);
PAINT AQUA (-4400 3675);
DISPLAY INVISIBLE (-4400 3675);
FORCEPROP 1 LAST BODY_TYPE PLUMBING
J 0
(-4520 3632);
DISPLAY 0.340426 (-4520 3632);
PAINT GREEN (-4520 3632);
DISPLAY INVISIBLE (-4520 3632);
FORCEPROP 2 LAST BOM_COST SM_CONTROLLER
J 0
(-4925 3750);
DISPLAY 1.617021 (-4925 3750);
PAINT WHITE (-4925 3750);
DISPLAY INVISIBLE (-4925 3750);
FORCEPROP 2 LAST CDS_LIB mstr_symbols
J 0
(-4475 3675);
DISPLAY 2.127660 (-4475 3675);
PAINT ORANGE (-4475 3675);
DISPLAY INVISIBLE (-4475 3675);
FORCEPROP 1 LAST SIZE 1B
J 0
(-4400 3625);
DISPLAY 1.127660 (-4400 3625);
PAINT GREEN (-4400 3625);
DISPLAY INVISIBLE (-4400 3625);
FORCEPROP 1 LAST VOLTAGE 0.0V
J 0
(-4520 3632);
DISPLAY 0.340426 (-4520 3632);
PAINT SKYBLUE (-4520 3632);
DISPLAY INVISIBLE (-4520 3632);
FORCEADD GND..1
(-6600 3625);
FORCEPROP 3 LASTPIN (-6600 3675) SIG_NAME GND\g
J 0
(-6590 3685);
DISPLAY 0.659574 (-6590 3685);
PAINT MONO (-6590 3685);
DISPLAY INVISIBLE (-6590 3685);
FORCEPROP 1 LAST HDL_POWER GND
J 0
(-6600 3775);
PAINT GREEN (-6600 3775);
DISPLAY INVISIBLE (-6600 3775);
FORCEPROP 2 LAST ROOM SYS_CLOCK
J 0
(-6920 3705);
DISPLAY 1.127660 (-6920 3705);
PAINT WHITE (-6920 3705);
DISPLAY INVISIBLE (-6920 3705);
FORCEPROP 1 LAST PATH I108
J 0
(-6525 3625);
DISPLAY 0.872340 (-6525 3625);
PAINT AQUA (-6525 3625);
DISPLAY INVISIBLE (-6525 3625);
FORCEPROP 1 LAST BODY_TYPE PLUMBING
J 0
(-6645 3582);
DISPLAY 0.340426 (-6645 3582);
PAINT GREEN (-6645 3582);
DISPLAY INVISIBLE (-6645 3582);
FORCEPROP 1 LAST SIZE 1B
J 0
(-6525 3575);
DISPLAY 1.127660 (-6525 3575);
PAINT GREEN (-6525 3575);
DISPLAY INVISIBLE (-6525 3575);
FORCEPROP 2 LAST CDS_LIB mstr_symbols
J 0
(-6600 3625);
DISPLAY 2.127660 (-6600 3625);
PAINT ORANGE (-6600 3625);
DISPLAY INVISIBLE (-6600 3625);
FORCEPROP 2 LAST BOM_COST SM_CONTROLLER
J 0
(-7045 3705);
DISPLAY 1.617021 (-7045 3705);
PAINT WHITE (-7045 3705);
DISPLAY INVISIBLE (-7045 3705);
FORCEPROP 1 LAST VOLTAGE 0.0V
J 0
(-6645 3582);
DISPLAY 0.340426 (-6645 3582);
PAINT SKYBLUE (-6645 3582);
DISPLAY INVISIBLE (-6645 3582);
FORCEADD CAP_A..1
(-6600 3975);
FORCEPROP 1 LASTPIN (-6600 3875) $PN 2
J 0
(-6590 3855);
DISPLAY 0.617021 (-6590 3855);
PAINT ORANGE (-6590 3855);
FORCEPROP 1 LASTPIN (-6600 4075) $PN 1
J 0
(-6590 4055);
DISPLAY 0.617021 (-6590 4055);
PAINT ORANGE (-6590 4055);
FORCEPROP 1 LAST MATERIAL X7R
J 0
(-6550 3875);
DISPLAY 0.617021 (-6550 3875);
PAINT SKYBLUE (-6550 3875);
FORCEPROP 1 LAST VOLTAGE 16V
J 0
(-6550 3975);
DISPLAY 0.617021 (-6550 3975);
PAINT SKYBLUE (-6550 3975);
FORCEPROP 1 LAST PACK_TYPE 0402V
J 0
(-6550 3775);
DISPLAY 0.617021 (-6550 3775);
PAINT SKYBLUE (-6550 3775);
FORCEPROP 1 LAST TOLERANCE 10%
J 0
(-6550 3925);
DISPLAY 0.617021 (-6550 3925);
PAINT SKYBLUE (-6550 3925);
FORCEPROP 1 LAST VALUE 0.1UF
J 0
(-6550 4025);
DISPLAY 0.617021 (-6550 4025);
PAINT SKYBLUE (-6550 4025);
FORCEPROP 1 LAST PART_NUMBER A36096-030
J 0
(-6550 3825);
DISPLAY 0.617021 (-6550 3825);
PAINT BLUE (-6550 3825);
FORCEPROP 1 LAST LOCATION C2T34
J 0
(-6550 4075);
DISPLAY 0.617021 (-6550 4075);
PAINT AQUA (-6550 4075);
FORCEPROP 2 LAST SEC 1
J 0
(-6550 4175);
DISPLAY 0.680851 (-6550 4175);
PAINT MONO (-6550 4175);
DISPLAY INVISIBLE (-6550 4175);
FORCEPROP 2 LAST SEC_TYPE 0402V
J 0
(-6550 4175);
DISPLAY 1.021277 (-6550 4175);
PAINT ORANGE (-6550 4175);
DISPLAY INVISIBLE (-6550 4175);
FORCEPROP 2 LAST CDS_SEC 1
J 0
(-6550 4125);
PAINT ORANGE (-6550 4125);
DISPLAY INVISIBLE (-6550 4125);
FORCEPROP 2 LAST CDS_LIB dev_discrete
J 0
(-6600 3975);
PAINT ORANGE (-6600 3975);
DISPLAY INVISIBLE (-6600 3975);
FORCEPROP 2 LAST BOM_COST SM_CONTROLLER
J 0
(-6550 4100);
DISPLAY 1.617021 (-6550 4100);
PAINT WHITE (-6550 4100);
DISPLAY INVISIBLE (-6550 4100);
FORCEPROP 2 LAST CDS_LOCATION C2T34
J 0
(-6550 4075);
DISPLAY 0.617021 (-6550 4075);
PAINT AQUA (-6550 4075);
DISPLAY INVISIBLE (-6550 4075);
FORCEPROP 2 LAST ROOM SYS_CLOCK
J 0
(-6550 4125);
DISPLAY 1.127660 (-6550 4125);
PAINT WHITE (-6550 4125);
DISPLAY INVISIBLE (-6550 4125);
FORCEPROP 1 LAST PATH I109
J 0
(-6550 4125);
DISPLAY 0.978723 (-6550 4125);
PAINT WHITE (-6550 4125);
DISPLAY INVISIBLE (-6550 4125);
FORCEADD CAP_A..1
(-6900 3975);
FORCEPROP 1 LASTPIN (-6900 3875) $PN 2
J 0
(-6890 3855);
DISPLAY 0.617021 (-6890 3855);
PAINT WHITE (-6890 3855);
FORCEPROP 1 LASTPIN (-6900 4075) $PN 1
J 0
(-6890 4055);
DISPLAY 0.617021 (-6890 4055);
PAINT WHITE (-6890 4055);
FORCEPROP 1 LAST MATERIAL X7R
J 0
(-6850 3875);
DISPLAY 0.617021 (-6850 3875);
PAINT SKYBLUE (-6850 3875);
FORCEPROP 1 LAST VOLTAGE 16V
J 0
(-6850 3975);
DISPLAY 0.617021 (-6850 3975);
PAINT SKYBLUE (-6850 3975);
FORCEPROP 1 LAST PACK_TYPE 0402V
J 0
(-6850 3775);
DISPLAY 0.617021 (-6850 3775);
PAINT SKYBLUE (-6850 3775);
FORCEPROP 1 LAST TOLERANCE 10%
J 0
(-6850 3925);
DISPLAY 0.617021 (-6850 3925);
PAINT SKYBLUE (-6850 3925);
FORCEPROP 1 LAST VALUE 0.1UF
J 0
(-6850 4025);
DISPLAY 0.617021 (-6850 4025);
PAINT SKYBLUE (-6850 4025);
FORCEPROP 1 LAST PART_NUMBER A36096-030
J 0
(-6850 3825);
DISPLAY 0.617021 (-6850 3825);
PAINT BLUE (-6850 3825);
FORCEPROP 1 LAST LOCATION C2T30
J 0
(-6850 4075);
DISPLAY 0.617021 (-6850 4075);
PAINT AQUA (-6850 4075);
FORCEPROP 2 LAST $SEC 1
J 0
(-6850 4175);
DISPLAY 1.510638 (-6850 4175);
PAINT MONO (-6850 4175);
DISPLAY INVISIBLE (-6850 4175);
FORCEPROP 2 LAST CDS_SEC 1
J 0
(-6850 4175);
DISPLAY 2.276596 (-6850 4175);
PAINT ORANGE (-6850 4175);
DISPLAY INVISIBLE (-6850 4175);
FORCEPROP 2 LAST CDS_LIB dev_discrete
J 0
(-6900 3975);
PAINT ORANGE (-6900 3975);
DISPLAY INVISIBLE (-6900 3975);
FORCEPROP 2 LAST BOM_COST SM_CONTROLLER
J 0
(-6850 4100);
DISPLAY 1.617021 (-6850 4100);
PAINT WHITE (-6850 4100);
DISPLAY INVISIBLE (-6850 4100);
FORCEPROP 2 LAST CDS_LOCATION C2T30
J 0
(-6850 4075);
DISPLAY 0.617021 (-6850 4075);
PAINT AQUA (-6850 4075);
DISPLAY INVISIBLE (-6850 4075);
FORCEPROP 2 LAST ROOM SYS_CLOCK
J 0
(-6850 4125);
DISPLAY 1.127660 (-6850 4125);
PAINT WHITE (-6850 4125);
DISPLAY INVISIBLE (-6850 4125);
FORCEPROP 1 LAST PATH I110
J 0
(-6850 4125);
DISPLAY 0.978723 (-6850 4125);
PAINT WHITE (-6850 4125);
DISPLAY INVISIBLE (-6850 4125);
FORCEADD CAP_A..1
(-7300 3975);
FORCEPROP 1 LASTPIN (-7300 3875) $PN 2
J 0
(-7290 3855);
DISPLAY 0.617021 (-7290 3855);
PAINT WHITE (-7290 3855);
FORCEPROP 1 LASTPIN (-7300 4075) $PN 1
J 0
(-7290 4055);
DISPLAY 0.617021 (-7290 4055);
PAINT WHITE (-7290 4055);
FORCEPROP 1 LAST MATERIAL X7R
J 0
(-7250 3875);
DISPLAY 0.617021 (-7250 3875);
PAINT SKYBLUE (-7250 3875);
FORCEPROP 1 LAST VOLTAGE 16V
J 0
(-7250 3975);
DISPLAY 0.617021 (-7250 3975);
PAINT SKYBLUE (-7250 3975);
FORCEPROP 1 LAST PACK_TYPE 0402V
J 0
(-7250 3775);
DISPLAY 0.617021 (-7250 3775);
PAINT SKYBLUE (-7250 3775);
FORCEPROP 1 LAST TOLERANCE 10%
J 0
(-7250 3925);
DISPLAY 0.617021 (-7250 3925);
PAINT SKYBLUE (-7250 3925);
FORCEPROP 1 LAST VALUE 0.1UF
J 0
(-7250 4025);
DISPLAY 0.617021 (-7250 4025);
PAINT SKYBLUE (-7250 4025);
FORCEPROP 1 LAST PART_NUMBER A36096-030
J 0
(-7250 3825);
DISPLAY 0.617021 (-7250 3825);
PAINT BLUE (-7250 3825);
FORCEPROP 1 LAST LOCATION C2T25
J 0
(-7250 4075);
DISPLAY 0.617021 (-7250 4075);
PAINT AQUA (-7250 4075);
FORCEPROP 2 LAST $SEC 1
J 0
(-7250 4175);
DISPLAY 1.510638 (-7250 4175);
PAINT MONO (-7250 4175);
DISPLAY INVISIBLE (-7250 4175);
FORCEPROP 2 LAST CDS_SEC 1
J 0
(-7250 4175);
DISPLAY 2.276596 (-7250 4175);
PAINT ORANGE (-7250 4175);
DISPLAY INVISIBLE (-7250 4175);
FORCEPROP 2 LAST CDS_LIB dev_discrete
J 0
(-7300 3975);
PAINT ORANGE (-7300 3975);
DISPLAY INVISIBLE (-7300 3975);
FORCEPROP 2 LAST BOM_COST SM_CONTROLLER
J 0
(-7250 4100);
DISPLAY 1.617021 (-7250 4100);
PAINT WHITE (-7250 4100);
DISPLAY INVISIBLE (-7250 4100);
FORCEPROP 2 LAST CDS_LOCATION C2T25
J 0
(-7250 4075);
DISPLAY 0.617021 (-7250 4075);
PAINT AQUA (-7250 4075);
DISPLAY INVISIBLE (-7250 4075);
FORCEPROP 2 LAST ROOM SYS_CLOCK
J 0
(-7250 4125);
DISPLAY 1.127660 (-7250 4125);
PAINT WHITE (-7250 4125);
DISPLAY INVISIBLE (-7250 4125);
FORCEPROP 1 LAST PATH I111
J 0
(-7250 4125);
DISPLAY 0.978723 (-7250 4125);
PAINT WHITE (-7250 4125);
DISPLAY INVISIBLE (-7250 4125);
FORCEADD CAP_A..1
(-7600 3975);
FORCEPROP 1 LASTPIN (-7600 3875) $PN 2
J 0
(-7590 3855);
DISPLAY 0.617021 (-7590 3855);
PAINT WHITE (-7590 3855);
FORCEPROP 1 LASTPIN (-7600 4075) $PN 1
J 0
(-7590 4055);
DISPLAY 0.617021 (-7590 4055);
PAINT WHITE (-7590 4055);
FORCEPROP 1 LAST MATERIAL X7R
J 0
(-7550 3875);
DISPLAY 0.617021 (-7550 3875);
PAINT SKYBLUE (-7550 3875);
FORCEPROP 1 LAST VOLTAGE 16V
J 0
(-7550 3975);
DISPLAY 0.617021 (-7550 3975);
PAINT SKYBLUE (-7550 3975);
FORCEPROP 1 LAST PACK_TYPE 0402V
J 0
(-7550 3775);
DISPLAY 0.617021 (-7550 3775);
PAINT SKYBLUE (-7550 3775);
FORCEPROP 1 LAST TOLERANCE 10%
J 0
(-7550 3925);
DISPLAY 0.617021 (-7550 3925);
PAINT SKYBLUE (-7550 3925);
FORCEPROP 1 LAST VALUE 0.1UF
J 0
(-7550 4025);
DISPLAY 0.617021 (-7550 4025);
PAINT SKYBLUE (-7550 4025);
FORCEPROP 1 LAST PART_NUMBER A36096-030
J 0
(-7550 3825);
DISPLAY 0.617021 (-7550 3825);
PAINT BLUE (-7550 3825);
FORCEPROP 1 LAST LOCATION C2T17
J 0
(-7550 4075);
DISPLAY 0.617021 (-7550 4075);
PAINT AQUA (-7550 4075);
FORCEPROP 2 LAST $SEC 1
J 0
(-7550 4175);
DISPLAY 1.510638 (-7550 4175);
PAINT MONO (-7550 4175);
DISPLAY INVISIBLE (-7550 4175);
FORCEPROP 2 LAST CDS_SEC 1
J 0
(-7550 4175);
DISPLAY 2.276596 (-7550 4175);
PAINT ORANGE (-7550 4175);
DISPLAY INVISIBLE (-7550 4175);
FORCEPROP 2 LAST CDS_LIB dev_discrete
J 0
(-7600 3975);
PAINT ORANGE (-7600 3975);
DISPLAY INVISIBLE (-7600 3975);
FORCEPROP 2 LAST BOM_COST SM_CONTROLLER
J 0
(-7550 4100);
DISPLAY 1.617021 (-7550 4100);
PAINT WHITE (-7550 4100);
DISPLAY INVISIBLE (-7550 4100);
FORCEPROP 2 LAST CDS_LOCATION C2T17
J 0
(-7550 4075);
DISPLAY 0.617021 (-7550 4075);
PAINT AQUA (-7550 4075);
DISPLAY INVISIBLE (-7550 4075);
FORCEPROP 2 LAST ROOM SYS_CLOCK
J 0
(-7550 4125);
DISPLAY 1.127660 (-7550 4125);
PAINT WHITE (-7550 4125);
DISPLAY INVISIBLE (-7550 4125);
FORCEPROP 1 LAST PATH I112
J 0
(-7550 4125);
DISPLAY 0.978723 (-7550 4125);
PAINT WHITE (-7550 4125);
DISPLAY INVISIBLE (-7550 4125);
FORCEADD CAP..1
(-7900 3975);
FORCEPROP 1 LASTPIN (-7900 4075) $PN 1
J 0
(-7890 4055);
DISPLAY 0.617021 (-7890 4055);
PAINT WHITE (-7890 4055);
FORCEPROP 1 LASTPIN (-7900 3875) $PN 2
J 0
(-7890 3855);
DISPLAY 0.617021 (-7890 3855);
PAINT WHITE (-7890 3855);
FORCEPROP 1 LAST MATERIAL X6S
J 0
(-7850 3875);
DISPLAY 0.617021 (-7850 3875);
PAINT SKYBLUE (-7850 3875);
FORCEPROP 1 LAST VOLTAGE 16V
J 0
(-7850 3975);
DISPLAY 0.617021 (-7850 3975);
PAINT SKYBLUE (-7850 3975);
FORCEPROP 1 LAST PACK_TYPE 0805
J 0
(-7850 3775);
DISPLAY 0.617021 (-7850 3775);
PAINT SKYBLUE (-7850 3775);
FORCEPROP 1 LAST TOLERANCE 10%
J 0
(-7850 3925);
DISPLAY 0.617021 (-7850 3925);
PAINT SKYBLUE (-7850 3925);
FORCEPROP 1 LAST VALUE 10UF
J 0
(-7850 4025);
DISPLAY 0.617021 (-7850 4025);
PAINT SKYBLUE (-7850 4025);
FORCEPROP 1 LAST PART_NUMBER C95333-007
J 0
(-7850 3825);
DISPLAY 0.617021 (-7850 3825);
PAINT BLUE (-7850 3825);
FORCEPROP 1 LAST LOCATION C2T22
J 0
(-7850 4075);
DISPLAY 0.617021 (-7850 4075);
PAINT AQUA (-7850 4075);
FORCEPROP 2 LAST ROOM SYS_CLOCK
J 0
(-7845 4125);
DISPLAY 1.127660 (-7845 4125);
PAINT WHITE (-7845 4125);
DISPLAY INVISIBLE (-7845 4125);
FORCEPROP 1 LAST PATH I113
J 0
(-7850 4125);
DISPLAY 0.978723 (-7850 4125);
PAINT WHITE (-7850 4125);
DISPLAY INVISIBLE (-7850 4125);
FORCEPROP 2 LAST CDS_LOCATION C2T22
J 0
(-7850 4075);
DISPLAY 0.617021 (-7850 4075);
PAINT AQUA (-7850 4075);
DISPLAY INVISIBLE (-7850 4075);
FORCEPROP 2 LAST SEC 1
J 0
(-7845 4175);
DISPLAY 1.510638 (-7845 4175);
PAINT MONO (-7845 4175);
DISPLAY INVISIBLE (-7845 4175);
FORCEPROP 2 LAST SEC_TYPE 0805
J 0
(-7850 4175);
DISPLAY 1.021277 (-7850 4175);
PAINT ORANGE (-7850 4175);
DISPLAY INVISIBLE (-7850 4175);
FORCEPROP 2 LAST BOM_COST SM_CONTROLLER
J 0
(-7845 4100);
DISPLAY 1.617021 (-7845 4100);
PAINT WHITE (-7845 4100);
DISPLAY INVISIBLE (-7845 4100);
FORCEPROP 2 LAST CDS_LIB mstr_discrete
J 0
(-7900 3975);
DISPLAY 1.617021 (-7900 3975);
PAINT ORANGE (-7900 3975);
DISPLAY INVISIBLE (-7900 3975);
FORCEADD FERRITE..1
(-8125 4125);
FORCEPROP 1 LASTPIN (-8225 4125) $PN 1
J 2
(-8190 4135);
DISPLAY 0.617021 (-8190 4135);
PAINT WHITE (-8190 4135);
FORCEPROP 1 LASTPIN (-8025 4125) $PN 2
J 0
(-8045 4135);
DISPLAY 0.617021 (-8045 4135);
PAINT WHITE (-8045 4135);
FORCEPROP 1 LAST MATERIAL FB
J 0
(-8070 4025);
DISPLAY 0.617021 (-8070 4025);
PAINT SKYBLUE (-8070 4025);
FORCEPROP 1 LAST PACK_TYPE SMLF
J 0
(-8195 3975);
DISPLAY 0.617021 (-8195 3975);
PAINT SKYBLUE (-8195 3975);
FORCEPROP 1 LAST VALUE 600
J 2
(-8120 4025);
DISPLAY 0.617021 (-8120 4025);
PAINT SKYBLUE (-8120 4025);
FORCEPROP 1 LAST PART_NUMBER 656554-043
J 0
(-8220 4240);
DISPLAY 0.617021 (-8220 4240);
PAINT BLUE (-8220 4240);
FORCEPROP 1 LAST LOCATION FB2T2
J 0
(-8220 4180);
DISPLAY 0.617021 (-8220 4180);
PAINT AQUA (-8220 4180);
FORCEPROP 2 LAST ROOM SYS_CLOCK
J 0
(-8200 4275);
DISPLAY 1.127660 (-8200 4275);
PAINT WHITE (-8200 4275);
DISPLAY INVISIBLE (-8200 4275);
FORCEPROP 1 LAST PATH I114
J 0
(-8220 4290);
DISPLAY 0.872340 (-8220 4290);
PAINT PURPLE (-8220 4290);
DISPLAY INVISIBLE (-8220 4290);
FORCEPROP 2 LAST CDS_LOCATION FB2T2
J 0
(-8220 4180);
DISPLAY 0.617021 (-8220 4180);
PAINT AQUA (-8220 4180);
DISPLAY INVISIBLE (-8220 4180);
FORCEPROP 2 LAST $SEC 1
J 0
(-8200 4350);
DISPLAY 1.510638 (-8200 4350);
PAINT MONO (-8200 4350);
DISPLAY INVISIBLE (-8200 4350);
FORCEPROP 2 LAST CDS_SEC 1
J 0
(-8200 4350);
DISPLAY 1.659574 (-8200 4350);
PAINT ORANGE (-8200 4350);
DISPLAY INVISIBLE (-8200 4350);
FORCEPROP 2 LAST CDS_LIB mstr_discrete
J 0
(-8125 4125);
DISPLAY 2.127660 (-8125 4125);
PAINT GREEN (-8125 4125);
DISPLAY INVISIBLE (-8125 4125);
FORCEPROP 2 LAST BOM_COST SM_CONTROLLER
J 0
(-8200 4275);
DISPLAY 1.617021 (-8200 4275);
PAINT WHITE (-8200 4275);
DISPLAY INVISIBLE (-8200 4275);
FORCEADD P3V3_STBY..1
(-8475 4350);
FORCEPROP 3 LASTPIN (-8475 4300) SIG_NAME P3V3_STBY\g
J 0
(-8465 4310);
DISPLAY 0.659574 (-8465 4310);
PAINT MONO (-8465 4310);
DISPLAY INVISIBLE (-8465 4310);
FORCEPROP 1 LAST HDL_POWER P3V3_STBY
J 0
(-8775 4225);
DISPLAY 0.872340 (-8775 4225);
PAINT ORANGE (-8775 4225);
DISPLAY INVISIBLE (-8775 4225);
FORCEPROP 1 LAST PATH I115
J 0
(-8430 4352);
DISPLAY 0.340426 (-8430 4352);
PAINT GREEN (-8430 4352);
DISPLAY INVISIBLE (-8430 4352);
FORCEPROP 1 LAST BODY_TYPE PLUMBING
J 0
(-8520 4307);
DISPLAY 0.340426 (-8520 4307);
PAINT GREEN (-8520 4307);
DISPLAY INVISIBLE (-8520 4307);
FORCEPROP 2 LAST CDS_LIB mstr_symbols
J 0
(-8475 4350);
PAINT ORANGE (-8475 4350);
DISPLAY INVISIBLE (-8475 4350);
FORCEPROP 1 LAST SIZE 1B
J 0
(-8430 4372);
DISPLAY 0.340426 (-8430 4372);
PAINT GREEN (-8430 4372);
DISPLAY INVISIBLE (-8430 4372);
FORCEPROP 1 LAST VOLTAGE 3.3
J 0
(-8275 4500);
DISPLAY 1.021277 (-8275 4500);
PAINT SKYBLUE (-8275 4500);
DISPLAY INVISIBLE (-8275 4500);
FORCEADD CAP_A..1
(-8475 3950);
FORCEPROP 1 LASTPIN (-8475 3850) $PN 2
J 0
(-8465 3830);
DISPLAY 0.617021 (-8465 3830);
PAINT WHITE (-8465 3830);
FORCEPROP 1 LASTPIN (-8475 4050) $PN 1
J 0
(-8465 4030);
DISPLAY 0.617021 (-8465 4030);
PAINT WHITE (-8465 4030);
FORCEPROP 1 LAST MATERIAL X6S
J 0
(-8425 3850);
DISPLAY 0.617021 (-8425 3850);
PAINT SKYBLUE (-8425 3850);
FORCEPROP 1 LAST VOLTAGE 6.3V
J 0
(-8425 3950);
DISPLAY 0.617021 (-8425 3950);
PAINT SKYBLUE (-8425 3950);
FORCEPROP 1 LAST PACK_TYPE 0402V
J 0
(-8425 3750);
DISPLAY 0.617021 (-8425 3750);
PAINT SKYBLUE (-8425 3750);
FORCEPROP 1 LAST TOLERANCE 10%
J 0
(-8425 3900);
DISPLAY 0.617021 (-8425 3900);
PAINT SKYBLUE (-8425 3900);
FORCEPROP 1 LAST VALUE 1.0UF
J 0
(-8425 4000);
DISPLAY 0.617021 (-8425 4000);
PAINT SKYBLUE (-8425 4000);
FORCEPROP 1 LAST PART_NUMBER D97712-004
J 0
(-8425 3800);
DISPLAY 0.617021 (-8425 3800);
PAINT BLUE (-8425 3800);
FORCEPROP 1 LAST LOCATION C2T28
J 0
(-8425 4050);
DISPLAY 0.617021 (-8425 4050);
PAINT AQUA (-8425 4050);
FORCEPROP 2 LAST ROOM SYS_CLOCK
J 0
(-8425 4100);
DISPLAY 1.127660 (-8425 4100);
PAINT WHITE (-8425 4100);
DISPLAY INVISIBLE (-8425 4100);
FORCEPROP 1 LAST PATH I116
J 0
(-8425 4100);
DISPLAY 0.978723 (-8425 4100);
PAINT WHITE (-8425 4100);
DISPLAY INVISIBLE (-8425 4100);
FORCEPROP 2 LAST $SEC 1
J 0
(-8425 4150);
DISPLAY 1.510638 (-8425 4150);
PAINT MONO (-8425 4150);
DISPLAY INVISIBLE (-8425 4150);
FORCEPROP 2 LAST CDS_SEC 1
J 0
(-8425 4150);
DISPLAY 1.659574 (-8425 4150);
PAINT ORANGE (-8425 4150);
DISPLAY INVISIBLE (-8425 4150);
FORCEPROP 2 LAST CDS_LIB dev_discrete
J 0
(-8475 3950);
PAINT ORANGE (-8475 3950);
DISPLAY INVISIBLE (-8475 3950);
FORCEPROP 2 LAST BOM_COST SM_CONTROLLER
J 0
(-8425 4075);
DISPLAY 1.617021 (-8425 4075);
PAINT WHITE (-8425 4075);
DISPLAY INVISIBLE (-8425 4075);
FORCEPROP 2 LAST CDS_LOCATION C2T28
J 0
(-8425 4050);
DISPLAY 0.617021 (-8425 4050);
PAINT AQUA (-8425 4050);
DISPLAY INVISIBLE (-8425 4050);
FORCEADD VCC_CORE..1
(-6600 4275);
FORCEPROP 3 LASTPIN (-6600 4225) SIG_NAME P3V3_STBY_MNG\g
J 0
(-6590 4235);
DISPLAY 0.659574 (-6590 4235);
PAINT MONO (-6590 4235);
DISPLAY INVISIBLE (-6590 4235);
FORCEPROP 1 LAST HDL_POWER P3V3_STBY_MNG
J 1
(-6550 4325);
DISPLAY 0.617021 (-6550 4325);
PAINT GREEN (-6550 4325);
FORCEPROP 1 LAST PATH I117
J 0
(-6550 4300);
DISPLAY 0.872340 (-6550 4300);
PAINT AQUA (-6550 4300);
DISPLAY INVISIBLE (-6550 4300);
FORCEPROP 2 LAST CDS_LIB mstr_symbols
J 0
(-6600 4275);
PAINT ORANGE (-6600 4275);
DISPLAY INVISIBLE (-6600 4275);
FORCEPROP 0 LAST VOLTAGE 5
J 0
(-6600 4275);
PAINT SKYBLUE (-6600 4275);
DISPLAY INVISIBLE (-6600 4275);
FORCEADD VCC_CORE..1
(-5425 4375);
FORCEPROP 3 LASTPIN (-5425 4325) SIG_NAME P3V3_STBY_MNG\g
J 0
(-5415 4335);
DISPLAY 0.659574 (-5415 4335);
PAINT MONO (-5415 4335);
DISPLAY INVISIBLE (-5415 4335);
FORCEPROP 1 LAST HDL_POWER P3V3_STBY_MNG
J 1
(-5375 4425);
DISPLAY 0.617021 (-5375 4425);
PAINT GREEN (-5375 4425);
FORCEPROP 1 LAST PATH I118
J 0
(-5375 4400);
DISPLAY 0.872340 (-5375 4400);
PAINT AQUA (-5375 4400);
DISPLAY INVISIBLE (-5375 4400);
FORCEPROP 2 LAST CDS_LIB mstr_symbols
J 0
(-5425 4375);
PAINT ORANGE (-5425 4375);
DISPLAY INVISIBLE (-5425 4375);
FORCEPROP 0 LAST VOLTAGE 5
J 0
(-5425 4375);
PAINT SKYBLUE (-5425 4375);
DISPLAY INVISIBLE (-5425 4375);
FORCEADD VCC_CORE..1
(-6675 3200);
FORCEPROP 3 LASTPIN (-6675 3150) SIG_NAME P3V3_STBY_MNG_RGMII\g
J 0
(-6665 3160);
DISPLAY 0.659574 (-6665 3160);
PAINT MONO (-6665 3160);
DISPLAY INVISIBLE (-6665 3160);
FORCEPROP 1 LAST HDL_POWER P3V3_STBY_MNG_RGMII
J 1
(-6625 3250);
DISPLAY 0.617021 (-6625 3250);
PAINT GREEN (-6625 3250);
FORCEPROP 1 LAST PATH I119
J 0
(-6625 3225);
DISPLAY 0.872340 (-6625 3225);
PAINT AQUA (-6625 3225);
DISPLAY INVISIBLE (-6625 3225);
FORCEPROP 2 LAST CDS_LIB mstr_symbols
J 0
(-6675 3200);
PAINT ORANGE (-6675 3200);
DISPLAY INVISIBLE (-6675 3200);
FORCEPROP 0 LAST VOLTAGE 3.3
J 0
(-6675 3200);
PAINT SKYBLUE (-6675 3200);
DISPLAY INVISIBLE (-6675 3200);
FORCEADD VCC_CORE..1
(-6975 3000);
FORCEPROP 3 LASTPIN (-6975 2950) SIG_NAME P3V3_STBY_MNG_RMII\g
J 0
(-6965 2960);
DISPLAY 0.659574 (-6965 2960);
PAINT MONO (-6965 2960);
DISPLAY INVISIBLE (-6965 2960);
FORCEPROP 1 LAST HDL_POWER P3V3_STBY_MNG_RMII
J 1
(-6925 3050);
DISPLAY 0.617021 (-6925 3050);
PAINT GREEN (-6925 3050);
FORCEPROP 1 LAST PATH I120
J 0
(-6925 3025);
DISPLAY 0.872340 (-6925 3025);
PAINT AQUA (-6925 3025);
DISPLAY INVISIBLE (-6925 3025);
FORCEPROP 2 LAST CDS_LIB mstr_symbols
J 0
(-6975 3000);
PAINT ORANGE (-6975 3000);
DISPLAY INVISIBLE (-6975 3000);
FORCEPROP 0 LAST VOLTAGE 3.3
J 0
(-6975 3000);
PAINT SKYBLUE (-6975 3000);
DISPLAY INVISIBLE (-6975 3000);
FORCEADD VCC_CORE..1
(-4475 4325);
FORCEPROP 3 LASTPIN (-4475 4275) SIG_NAME P3V3_STBY_MNG_CPU\g
J 0
(-4465 4285);
DISPLAY 0.659574 (-4465 4285);
PAINT MONO (-4465 4285);
DISPLAY INVISIBLE (-4465 4285);
FORCEPROP 1 LAST HDL_POWER P3V3_STBY_MNG_CPU
J 1
(-4425 4375);
DISPLAY 0.617021 (-4425 4375);
PAINT GREEN (-4425 4375);
FORCEPROP 1 LAST PATH I121
J 0
(-4425 4350);
DISPLAY 0.872340 (-4425 4350);
PAINT AQUA (-4425 4350);
DISPLAY INVISIBLE (-4425 4350);
FORCEPROP 2 LAST CDS_LIB mstr_symbols
J 0
(-4475 4325);
PAINT ORANGE (-4475 4325);
DISPLAY INVISIBLE (-4475 4325);
FORCEPROP 0 LAST VOLTAGE 3.3
J 0
(-4475 4325);
PAINT SKYBLUE (-4475 4325);
DISPLAY INVISIBLE (-4475 4325);
FORCEADD VCC_CORE..1
(-7375 2500);
FORCEPROP 3 LASTPIN (-7375 2450) SIG_NAME P3V3_STBY_MNG\g
J 0
(-7365 2460);
DISPLAY 0.659574 (-7365 2460);
PAINT MONO (-7365 2460);
DISPLAY INVISIBLE (-7365 2460);
FORCEPROP 1 LAST HDL_POWER P3V3_STBY_MNG
J 1
(-7325 2550);
DISPLAY 0.617021 (-7325 2550);
PAINT GREEN (-7325 2550);
FORCEPROP 1 LAST PATH I122
J 0
(-7325 2525);
DISPLAY 0.872340 (-7325 2525);
PAINT AQUA (-7325 2525);
DISPLAY INVISIBLE (-7325 2525);
FORCEPROP 2 LAST CDS_LIB mstr_symbols
J 0
(-7375 2500);
PAINT ORANGE (-7375 2500);
DISPLAY INVISIBLE (-7375 2500);
FORCEPROP 0 LAST VOLTAGE 5
J 0
(-7375 2500);
PAINT SKYBLUE (-7375 2500);
DISPLAY INVISIBLE (-7375 2500);
FORCEADD VCC_CORE..1
(-7875 2375);
FORCEPROP 3 LASTPIN (-7875 2325) SIG_NAME P3V3_STBY_MNG_CPU\g
J 0
(-7865 2335);
DISPLAY 0.659574 (-7865 2335);
PAINT MONO (-7865 2335);
DISPLAY INVISIBLE (-7865 2335);
FORCEPROP 1 LAST HDL_POWER P3V3_STBY_MNG_CPU
J 1
(-7825 2425);
DISPLAY 0.617021 (-7825 2425);
PAINT GREEN (-7825 2425);
FORCEPROP 1 LAST PATH I123
J 0
(-7825 2400);
DISPLAY 0.872340 (-7825 2400);
PAINT AQUA (-7825 2400);
DISPLAY INVISIBLE (-7825 2400);
FORCEPROP 2 LAST CDS_LIB mstr_symbols
J 0
(-7875 2375);
PAINT ORANGE (-7875 2375);
DISPLAY INVISIBLE (-7875 2375);
FORCEPROP 0 LAST VOLTAGE 3.3
J 0
(-7875 2375);
PAINT SKYBLUE (-7875 2375);
DISPLAY INVISIBLE (-7875 2375);
FORCEADD RES..1
(-3425 1525);
FORCEPROP 1 LASTPIN (-3525 1525) $PN 1
J 0
(-3513 1537);
DISPLAY 0.617021 (-3513 1537);
PAINT ORANGE (-3513 1537);
FORCEPROP 1 LASTPIN (-3325 1525) $PN 2
J 0
(-3363 1537);
DISPLAY 0.617021 (-3363 1537);
PAINT ORANGE (-3363 1537);
FORCEPROP 1 LAST WATTAGE 1/16W
J 0
(-3475 1475);
DISPLAY 0.617021 (-3475 1475);
PAINT SKYBLUE (-3475 1475);
FORCEPROP 1 LAST MATERIAL CHIP
J 0
(-3700 1475);
DISPLAY 0.617021 (-3700 1475);
PAINT SKYBLUE (-3700 1475);
FORCEPROP 1 LAST PACK_TYPE 0402
J 0
(-3325 1475);
DISPLAY 0.617021 (-3325 1475);
PAINT SKYBLUE (-3325 1475);
FORCEPROP 1 LAST TOLERANCE 1.0%
J 1
(-3525 1475);
DISPLAY 0.617021 (-3525 1475);
PAINT SKYBLUE (-3525 1475);
FORCEPROP 1 LAST VALUE 22.1
J 2
(-3525 1550);
DISPLAY 0.617021 (-3525 1550);
PAINT SKYBLUE (-3525 1550);
FORCEPROP 1 LAST PART_NUMBER G21796-250
J 0
(-3225 1475);
DISPLAY 0.617021 (-3225 1475);
PAINT BLUE (-3225 1475);
FORCEPROP 1 LAST LOCATION R2T42
J 1
(-3425 1550);
DISPLAY 0.617021 (-3425 1550);
PAINT AQUA (-3425 1550);
FORCEPROP 0 LAST ROOM SYS_CLOCK
J 0
(-3475 1725);
DISPLAY 1.021277 (-3475 1725);
PAINT ORANGE (-3475 1725);
DISPLAY INVISIBLE (-3475 1725);
FORCEPROP 1 LAST PATH I124
J 0
(-3475 1675);
DISPLAY 0.978723 (-3475 1675);
PAINT WHITE (-3475 1675);
DISPLAY INVISIBLE (-3475 1675);
FORCEPROP 2 LAST CDS_LOCATION R2T42
J 1
(-3425 1550);
DISPLAY 0.617021 (-3425 1550);
PAINT AQUA (-3425 1550);
DISPLAY INVISIBLE (-3425 1550);
FORCEPROP 2 LAST SEC 1
J 0
(-3475 1725);
DISPLAY 0.680851 (-3475 1725);
PAINT MONO (-3475 1725);
DISPLAY INVISIBLE (-3475 1725);
FORCEPROP 2 LAST SEC_TYPE 0402
J 0
(-3475 1725);
DISPLAY 1.021277 (-3475 1725);
PAINT ORANGE (-3475 1725);
DISPLAY INVISIBLE (-3475 1725);
FORCEPROP 2 LAST CDS_LIB mstr_discrete
J 0
(-3425 1525);
PAINT ORANGE (-3425 1525);
DISPLAY INVISIBLE (-3425 1525);
FORCEPROP 0 LAST BOM_COST SM_CONTROLLER
J 0
(-3475 1825);
DISPLAY 1.021277 (-3475 1825);
PAINT ORANGE (-3475 1825);
DISPLAY INVISIBLE (-3475 1825);
FORCEADD RES..1
(-3425 1675);
FORCEPROP 1 LASTPIN (-3525 1675) $PN 1
J 0
(-3513 1687);
DISPLAY 0.617021 (-3513 1687);
PAINT ORANGE (-3513 1687);
FORCEPROP 1 LASTPIN (-3325 1675) $PN 2
J 0
(-3363 1687);
DISPLAY 0.617021 (-3363 1687);
PAINT ORANGE (-3363 1687);
FORCEPROP 1 LAST WATTAGE 1/16W
J 0
(-3475 1625);
DISPLAY 0.617021 (-3475 1625);
PAINT SKYBLUE (-3475 1625);
FORCEPROP 1 LAST MATERIAL CHIP
J 0
(-3700 1625);
DISPLAY 0.617021 (-3700 1625);
PAINT SKYBLUE (-3700 1625);
FORCEPROP 1 LAST PACK_TYPE 0402
J 0
(-3325 1625);
DISPLAY 0.617021 (-3325 1625);
PAINT SKYBLUE (-3325 1625);
FORCEPROP 1 LAST TOLERANCE 1.0%
J 1
(-3525 1625);
DISPLAY 0.617021 (-3525 1625);
PAINT SKYBLUE (-3525 1625);
FORCEPROP 1 LAST VALUE 22.1
J 2
(-3525 1700);
DISPLAY 0.617021 (-3525 1700);
PAINT SKYBLUE (-3525 1700);
FORCEPROP 1 LAST PART_NUMBER G21796-250
J 0
(-3225 1625);
DISPLAY 0.617021 (-3225 1625);
PAINT BLUE (-3225 1625);
FORCEPROP 1 LAST LOCATION R2T46
J 1
(-3425 1700);
DISPLAY 0.617021 (-3425 1700);
PAINT AQUA (-3425 1700);
FORCEPROP 0 LAST ROOM SYS_CLOCK
J 0
(-3475 1875);
DISPLAY 1.021277 (-3475 1875);
PAINT ORANGE (-3475 1875);
DISPLAY INVISIBLE (-3475 1875);
FORCEPROP 1 LAST PATH I125
J 0
(-3475 1825);
DISPLAY 0.978723 (-3475 1825);
PAINT WHITE (-3475 1825);
DISPLAY INVISIBLE (-3475 1825);
FORCEPROP 2 LAST CDS_LOCATION R2T46
J 1
(-3425 1700);
DISPLAY 0.617021 (-3425 1700);
PAINT AQUA (-3425 1700);
DISPLAY INVISIBLE (-3425 1700);
FORCEPROP 2 LAST SEC 1
J 0
(-3475 1875);
DISPLAY 0.680851 (-3475 1875);
PAINT MONO (-3475 1875);
DISPLAY INVISIBLE (-3475 1875);
FORCEPROP 0 LAST BOM_COST SM_CONTROLLER
J 0
(-3475 1975);
DISPLAY 1.021277 (-3475 1975);
PAINT ORANGE (-3475 1975);
DISPLAY INVISIBLE (-3475 1975);
FORCEPROP 2 LAST CDS_LIB mstr_discrete
J 0
(-3425 1675);
PAINT ORANGE (-3425 1675);
DISPLAY INVISIBLE (-3425 1675);
FORCEPROP 2 LAST SEC_TYPE 0402
J 0
(-3475 1875);
DISPLAY 1.021277 (-3475 1875);
PAINT ORANGE (-3475 1875);
DISPLAY INVISIBLE (-3475 1875);
FORCEADD RES..1
(-3425 2750);
FORCEPROP 1 LASTPIN (-3525 2750) $PN 1
J 0
(-3513 2762);
DISPLAY 0.617021 (-3513 2762);
PAINT WHITE (-3513 2762);
FORCEPROP 1 LASTPIN (-3325 2750) $PN 2
J 0
(-3363 2762);
DISPLAY 0.617021 (-3363 2762);
PAINT WHITE (-3363 2762);
FORCEPROP 1 LAST WATTAGE 1/16W
J 0
(-3475 2700);
DISPLAY 0.617021 (-3475 2700);
PAINT SKYBLUE (-3475 2700);
FORCEPROP 1 LAST MATERIAL CHIP
J 0
(-3700 2700);
DISPLAY 0.617021 (-3700 2700);
PAINT SKYBLUE (-3700 2700);
FORCEPROP 1 LAST PACK_TYPE 0402
J 0
(-3325 2700);
DISPLAY 0.617021 (-3325 2700);
PAINT SKYBLUE (-3325 2700);
FORCEPROP 1 LAST TOLERANCE 1.0%
J 1
(-3525 2700);
DISPLAY 0.617021 (-3525 2700);
PAINT SKYBLUE (-3525 2700);
FORCEPROP 1 LAST VALUE 22.1
J 2
(-3550 2775);
DISPLAY 0.617021 (-3550 2775);
PAINT SKYBLUE (-3550 2775);
FORCEPROP 1 LAST PART_NUMBER G21796-250
J 0
(-3225 2700);
DISPLAY 0.617021 (-3225 2700);
PAINT BLUE (-3225 2700);
FORCEPROP 1 LAST LOCATION R8F27
J 0
(-3475 2800);
DISPLAY 0.617021 (-3475 2800);
PAINT AQUA (-3475 2800);
FORCEPROP 2 LAST ROOM SYS_CLOCK
J 0
(-3575 2900);
DISPLAY 1.127660 (-3575 2900);
PAINT WHITE (-3575 2900);
DISPLAY INVISIBLE (-3575 2900);
FORCEPROP 1 LAST PATH I129
J 0
(-3475 2900);
DISPLAY 0.978723 (-3475 2900);
PAINT WHITE (-3475 2900);
DISPLAY INVISIBLE (-3475 2900);
FORCEPROP 2 LAST CDS_LOCATION R8F27
J 0
(-3475 2800);
DISPLAY 0.617021 (-3475 2800);
PAINT AQUA (-3475 2800);
DISPLAY INVISIBLE (-3475 2800);
FORCEPROP 2 LAST $SEC 1
J 0
(-3475 2950);
DISPLAY 1.106383 (-3475 2950);
PAINT MONO (-3475 2950);
DISPLAY INVISIBLE (-3475 2950);
FORCEPROP 2 LAST CDS_SEC 1
J 0
(-3475 2950);
DISPLAY 1.659574 (-3475 2950);
PAINT ORANGE (-3475 2950);
DISPLAY INVISIBLE (-3475 2950);
FORCEPROP 2 LAST CDS_LIB mstr_discrete
J 0
(-3425 2750);
DISPLAY 1.617021 (-3425 2750);
PAINT ORANGE (-3425 2750);
DISPLAY INVISIBLE (-3425 2750);
FORCEPROP 2 LAST BOM_COST SM_CONTROLLER
J 0
(-3575 2875);
DISPLAY 1.617021 (-3575 2875);
PAINT WHITE (-3575 2875);
DISPLAY INVISIBLE (-3575 2875);
FORCEADD OFFPAGE..2
(-2250 2750);
FORCEPROP 2 LAST $XR0 190 
J 0
(-2061 2750);
DISPLAY 0.638298 (-2061 2750);
PAINT MONO (-2061 2750);
FORCEPROP 2 LAST PATH I13
J 0
(-1925 2800);
DISPLAY 1.021277 (-1925 2800);
PAINT ORANGE (-1925 2800);
DISPLAY INVISIBLE (-1925 2800);
FORCEPROP 1 LAST COMMENT_BODY TRUE
J 0
(-2295 2655);
DISPLAY 1.404255 (-2295 2655);
PAINT PEACH (-2295 2655);
DISPLAY INVISIBLE (-2295 2655);
FORCEPROP 1 LAST OFFPAGE TRUE
J 0
(-1925 2625);
PAINT GREEN (-1925 2625);
DISPLAY INVISIBLE (-1925 2625);
FORCEPROP 2 LAST CDS_LIB mstr_standard
J 0
(-2250 2750);
DISPLAY 1.617021 (-2250 2750);
PAINT MONO (-2250 2750);
DISPLAY INVISIBLE (-2250 2750);
FORCEADD RES..1
(-3425 2575);
FORCEPROP 1 LASTPIN (-3525 2575) $PN 1
J 0
(-3513 2587);
DISPLAY 0.617021 (-3513 2587);
PAINT ORANGE (-3513 2587);
FORCEPROP 1 LASTPIN (-3325 2575) $PN 2
J 0
(-3363 2587);
DISPLAY 0.617021 (-3363 2587);
PAINT ORANGE (-3363 2587);
FORCEPROP 1 LAST WATTAGE 1/16W
J 0
(-3475 2525);
DISPLAY 0.617021 (-3475 2525);
PAINT SKYBLUE (-3475 2525);
FORCEPROP 1 LAST MATERIAL CHIP
J 0
(-3700 2525);
DISPLAY 0.617021 (-3700 2525);
PAINT SKYBLUE (-3700 2525);
FORCEPROP 1 LAST PACK_TYPE 0402
J 0
(-3325 2525);
DISPLAY 0.617021 (-3325 2525);
PAINT SKYBLUE (-3325 2525);
FORCEPROP 1 LAST TOLERANCE 1%
J 1
(-3525 2525);
DISPLAY 0.617021 (-3525 2525);
PAINT SKYBLUE (-3525 2525);
FORCEPROP 1 LAST VALUE 33.2
J 2
(-3550 2600);
DISPLAY 0.617021 (-3550 2600);
PAINT SKYBLUE (-3550 2600);
FORCEPROP 1 LAST PART_NUMBER G21796-074
J 0
(-3225 2525);
DISPLAY 0.617021 (-3225 2525);
PAINT BLUE (-3225 2525);
FORCEPROP 1 LAST LOCATION R2T47
J 0
(-3475 2600);
DISPLAY 0.617021 (-3475 2600);
PAINT AQUA (-3475 2600);
FORCEPROP 2 LAST ROOM SYS_CLOCK
J 0
(-3475 2725);
DISPLAY 1.127660 (-3475 2725);
PAINT WHITE (-3475 2725);
DISPLAY INVISIBLE (-3475 2725);
FORCEPROP 1 LAST PATH I130
J 0
(-3475 2725);
DISPLAY 0.978723 (-3475 2725);
PAINT WHITE (-3475 2725);
DISPLAY INVISIBLE (-3475 2725);
FORCEPROP 2 LAST CDS_LOCATION R2T47
J 0
(-3475 2600);
DISPLAY 0.617021 (-3475 2600);
PAINT AQUA (-3475 2600);
DISPLAY INVISIBLE (-3475 2600);
FORCEPROP 2 LAST SEC 1
J 0
(-3475 2775);
PAINT MONO (-3475 2775);
DISPLAY INVISIBLE (-3475 2775);
FORCEPROP 2 LAST BOM_COST SM_CONTROLLER
J 0
(-3475 2700);
DISPLAY 1.617021 (-3475 2700);
PAINT WHITE (-3475 2700);
DISPLAY INVISIBLE (-3475 2700);
FORCEPROP 2 LAST CDS_LIB mstr_discrete
J 0
(-3425 2575);
PAINT ORANGE (-3425 2575);
DISPLAY INVISIBLE (-3425 2575);
FORCEPROP 2 LAST SEC_TYPE 0402
J 0
(-3475 2775);
DISPLAY 1.021277 (-3475 2775);
PAINT ORANGE (-3475 2775);
DISPLAY INVISIBLE (-3475 2775);
FORCEADD RES..1
(-3425 1975);
FORCEPROP 1 LASTPIN (-3525 1975) $PN 1
J 0
(-3513 1987);
DISPLAY 0.617021 (-3513 1987);
PAINT ORANGE (-3513 1987);
FORCEPROP 1 LASTPIN (-3325 1975) $PN 2
J 0
(-3363 1987);
DISPLAY 0.617021 (-3363 1987);
PAINT ORANGE (-3363 1987);
FORCEPROP 1 LAST WATTAGE 1/16W
J 2
(-3550 1925);
DISPLAY 0.617021 (-3550 1925);
PAINT SKYBLUE (-3550 1925);
FORCEPROP 1 LAST MATERIAL CHIP
J 0
(-3525 1925);
DISPLAY 0.617021 (-3525 1925);
PAINT SKYBLUE (-3525 1925);
FORCEPROP 1 LAST PACK_TYPE 0402
J 0
(-3300 1925);
DISPLAY 0.617021 (-3300 1925);
PAINT SKYBLUE (-3300 1925);
FORCEPROP 1 LAST TOLERANCE 1%
J 0
(-3375 1925);
DISPLAY 0.617021 (-3375 1925);
PAINT SKYBLUE (-3375 1925);
FORCEPROP 1 LAST VALUE 33.2
J 2
(-3550 2000);
DISPLAY 0.617021 (-3550 2000);
PAINT SKYBLUE (-3550 2000);
FORCEPROP 1 LAST PART_NUMBER G21796-074
J 0
(-3175 1925);
DISPLAY 0.617021 (-3175 1925);
PAINT BLUE (-3175 1925);
FORCEPROP 1 LAST LOCATION R8G25
J 0
(-3475 2025);
DISPLAY 0.617021 (-3475 2025);
PAINT AQUA (-3475 2025);
FORCEPROP 1 LAST PATH I131
J 0
(-3475 2125);
DISPLAY 0.978723 (-3475 2125);
PAINT WHITE (-3475 2125);
DISPLAY INVISIBLE (-3475 2125);
FORCEPROP 2 LAST SEC 1
J 0
(-3475 2175);
DISPLAY 0.680851 (-3475 2175);
PAINT MONO (-3475 2175);
DISPLAY INVISIBLE (-3475 2175);
FORCEPROP 2 LAST SEC_TYPE 0402
J 0
(-3475 2175);
DISPLAY 1.021277 (-3475 2175);
PAINT ORANGE (-3475 2175);
DISPLAY INVISIBLE (-3475 2175);
FORCEPROP 2 LAST CDS_LIB mstr_discrete
J 0
(-3425 1975);
PAINT ORANGE (-3425 1975);
DISPLAY INVISIBLE (-3425 1975);
FORCEPROP 2 LAST CDS_LOCATION R8G25
J 0
(-3475 2025);
DISPLAY 0.617021 (-3475 2025);
PAINT AQUA (-3475 2025);
DISPLAY INVISIBLE (-3475 2025);
FORCEADD RES..1
(-3425 2125);
FORCEPROP 1 LASTPIN (-3525 2125) $PN 1
J 0
(-3513 2137);
DISPLAY 0.617021 (-3513 2137);
PAINT ORANGE (-3513 2137);
FORCEPROP 1 LASTPIN (-3325 2125) $PN 2
J 0
(-3363 2137);
DISPLAY 0.617021 (-3363 2137);
PAINT ORANGE (-3363 2137);
FORCEPROP 1 LAST WATTAGE 1/16W
J 2
(-3550 2075);
DISPLAY 0.617021 (-3550 2075);
PAINT SKYBLUE (-3550 2075);
FORCEPROP 1 LAST MATERIAL CHIP
J 0
(-3525 2075);
DISPLAY 0.617021 (-3525 2075);
PAINT SKYBLUE (-3525 2075);
FORCEPROP 1 LAST PACK_TYPE 0402
J 0
(-3300 2075);
DISPLAY 0.617021 (-3300 2075);
PAINT SKYBLUE (-3300 2075);
FORCEPROP 1 LAST TOLERANCE 1%
J 0
(-3375 2075);
DISPLAY 0.617021 (-3375 2075);
PAINT SKYBLUE (-3375 2075);
FORCEPROP 1 LAST VALUE 33.2
J 2
(-3550 2125);
DISPLAY 0.617021 (-3550 2125);
PAINT SKYBLUE (-3550 2125);
FORCEPROP 1 LAST PART_NUMBER G21796-074
J 0
(-3200 2075);
DISPLAY 0.617021 (-3200 2075);
PAINT BLUE (-3200 2075);
FORCEPROP 1 LAST LOCATION R8G24
J 0
(-3475 2175);
DISPLAY 0.617021 (-3475 2175);
PAINT AQUA (-3475 2175);
FORCEPROP 0 LAST ROOM SB
J 0
(-3250 2225);
DISPLAY 1.021277 (-3250 2225);
PAINT ORANGE (-3250 2225);
DISPLAY INVISIBLE (-3250 2225);
FORCEPROP 1 LAST PATH I132
J 0
(-3475 2275);
DISPLAY 0.978723 (-3475 2275);
PAINT WHITE (-3475 2275);
DISPLAY INVISIBLE (-3475 2275);
FORCEPROP 2 LAST SEC 1
J 0
(-3475 2325);
PAINT MONO (-3475 2325);
DISPLAY INVISIBLE (-3475 2325);
FORCEPROP 2 LAST SEC_TYPE 0402
J 0
(-3475 2325);
DISPLAY 1.021277 (-3475 2325);
PAINT ORANGE (-3475 2325);
DISPLAY INVISIBLE (-3475 2325);
FORCEPROP 2 LAST CDS_LIB mstr_discrete
J 0
(-3425 2125);
PAINT ORANGE (-3425 2125);
DISPLAY INVISIBLE (-3425 2125);
FORCEPROP 2 LAST CDS_LOCATION R8G24
J 0
(-3475 2175);
DISPLAY 0.617021 (-3475 2175);
PAINT AQUA (-3475 2175);
DISPLAY INVISIBLE (-3475 2175);
FORCEADD RES..1
(-3425 1825);
FORCEPROP 1 LASTPIN (-3525 1825) $PN 1
J 0
(-3513 1837);
DISPLAY 0.617021 (-3513 1837);
PAINT ORANGE (-3513 1837);
FORCEPROP 1 LASTPIN (-3325 1825) $PN 2
J 0
(-3363 1837);
DISPLAY 0.617021 (-3363 1837);
PAINT ORANGE (-3363 1837);
FORCEPROP 1 LAST WATTAGE 1/16W
J 2
(-3550 1775);
DISPLAY 0.617021 (-3550 1775);
PAINT SKYBLUE (-3550 1775);
FORCEPROP 1 LAST MATERIAL CHIP
J 0
(-3525 1775);
DISPLAY 0.617021 (-3525 1775);
PAINT SKYBLUE (-3525 1775);
FORCEPROP 1 LAST PACK_TYPE 0402
J 0
(-3300 1775);
DISPLAY 0.617021 (-3300 1775);
PAINT SKYBLUE (-3300 1775);
FORCEPROP 1 LAST TOLERANCE 1%
J 0
(-3375 1775);
DISPLAY 0.617021 (-3375 1775);
PAINT SKYBLUE (-3375 1775);
FORCEPROP 1 LAST VALUE 33.2
J 2
(-3525 1850);
DISPLAY 0.617021 (-3525 1850);
PAINT SKYBLUE (-3525 1850);
FORCEPROP 1 LAST PART_NUMBER G21796-074
J 0
(-3175 1775);
DISPLAY 0.617021 (-3175 1775);
PAINT BLUE (-3175 1775);
FORCEPROP 1 LAST LOCATION R8G1
J 0
(-3475 1875);
DISPLAY 0.617021 (-3475 1875);
PAINT AQUA (-3475 1875);
FORCEPROP 1 LAST PATH I133
J 0
(-3475 1975);
DISPLAY 0.978723 (-3475 1975);
PAINT WHITE (-3475 1975);
DISPLAY INVISIBLE (-3475 1975);
FORCEPROP 2 LAST CDS_LOCATION R8G1
J 0
(-3475 1875);
DISPLAY 0.617021 (-3475 1875);
PAINT AQUA (-3475 1875);
DISPLAY INVISIBLE (-3475 1875);
FORCEPROP 2 LAST $SEC 1
J 0
(-3475 2025);
PAINT MONO (-3475 2025);
DISPLAY INVISIBLE (-3475 2025);
FORCEPROP 2 LAST CDS_SEC 1
J 0
(-3475 2025);
PAINT MONO (-3475 2025);
DISPLAY INVISIBLE (-3475 2025);
FORCEPROP 2 LAST CDS_LIB mstr_discrete
J 0
(-3425 1825);
PAINT ORANGE (-3425 1825);
DISPLAY INVISIBLE (-3425 1825);
FORCEADD OFFPAGE..2
(-2250 2425);
FORCEPROP 2 LAST $XR0 145 
J 0
(-2061 2425);
DISPLAY 0.638298 (-2061 2425);
PAINT MONO (-2061 2425);
FORCEPROP 2 LAST PATH I14
J 0
(-2050 2475);
DISPLAY 1.021277 (-2050 2475);
PAINT ORANGE (-2050 2475);
DISPLAY INVISIBLE (-2050 2475);
FORCEPROP 1 LAST COMMENT_BODY TRUE
J 0
(-2295 2330);
DISPLAY 1.404255 (-2295 2330);
PAINT PEACH (-2295 2330);
DISPLAY INVISIBLE (-2295 2330);
FORCEPROP 1 LAST OFFPAGE TRUE
J 0
(-1925 2300);
PAINT GREEN (-1925 2300);
DISPLAY INVISIBLE (-1925 2300);
FORCEPROP 2 LAST CDS_LIB mstr_standard
J 0
(-2250 2425);
DISPLAY 1.617021 (-2250 2425);
PAINT MONO (-2250 2425);
DISPLAY INVISIBLE (-2250 2425);
FORCEADD RES..1
(-3425 2425);
FORCEPROP 1 LASTPIN (-3525 2425) $PN 1
J 0
(-3513 2437);
DISPLAY 0.617021 (-3513 2437);
PAINT WHITE (-3513 2437);
FORCEPROP 1 LASTPIN (-3325 2425) $PN 2
J 0
(-3363 2437);
DISPLAY 0.617021 (-3363 2437);
PAINT WHITE (-3363 2437);
FORCEPROP 1 LAST WATTAGE 1/16W
J 0
(-3475 2375);
DISPLAY 0.617021 (-3475 2375);
PAINT SKYBLUE (-3475 2375);
FORCEPROP 1 LAST MATERIAL CHIP
J 0
(-3700 2375);
DISPLAY 0.617021 (-3700 2375);
PAINT SKYBLUE (-3700 2375);
FORCEPROP 1 LAST PACK_TYPE 0402
J 0
(-3325 2375);
DISPLAY 0.617021 (-3325 2375);
PAINT SKYBLUE (-3325 2375);
FORCEPROP 1 LAST TOLERANCE 1%
J 1
(-3525 2375);
DISPLAY 0.617021 (-3525 2375);
PAINT SKYBLUE (-3525 2375);
FORCEPROP 1 LAST VALUE 33.2
J 2
(-3525 2450);
DISPLAY 0.617021 (-3525 2450);
PAINT SKYBLUE (-3525 2450);
FORCEPROP 1 LAST PART_NUMBER G21796-074
J 0
(-3225 2375);
DISPLAY 0.617021 (-3225 2375);
PAINT BLUE (-3225 2375);
FORCEPROP 1 LAST LOCATION R8F29
J 0
(-3475 2450);
DISPLAY 0.617021 (-3475 2450);
PAINT AQUA (-3475 2450);
FORCEPROP 2 LAST ROOM SYS_CLOCK
J 0
(-3475 2575);
DISPLAY 1.127660 (-3475 2575);
PAINT WHITE (-3475 2575);
DISPLAY INVISIBLE (-3475 2575);
FORCEPROP 1 LAST PATH I20
J 0
(-3475 2575);
DISPLAY 0.978723 (-3475 2575);
PAINT WHITE (-3475 2575);
DISPLAY INVISIBLE (-3475 2575);
FORCEPROP 2 LAST CDS_LOCATION R8F29
J 0
(-3475 2450);
DISPLAY 0.617021 (-3475 2450);
PAINT AQUA (-3475 2450);
DISPLAY INVISIBLE (-3475 2450);
FORCEPROP 2 LAST SEC 1
J 0
(-3475 2625);
DISPLAY 1.510638 (-3475 2625);
PAINT MONO (-3475 2625);
DISPLAY INVISIBLE (-3475 2625);
FORCEPROP 2 LAST CDS_LIB mstr_discrete
J 0
(-3425 2425);
DISPLAY 1.617021 (-3425 2425);
PAINT ORANGE (-3425 2425);
DISPLAY INVISIBLE (-3425 2425);
FORCEPROP 2 LAST SEC_TYPE 0402
J 0
(-3475 2625);
DISPLAY 1.659574 (-3475 2625);
PAINT ORANGE (-3475 2625);
DISPLAY INVISIBLE (-3475 2625);
FORCEPROP 2 LAST BOM_COST SM_CONTROLLER
J 0
(-3475 2550);
DISPLAY 1.617021 (-3475 2550);
PAINT WHITE (-3475 2550);
DISPLAY INVISIBLE (-3475 2550);
FORCEADD RES..2
R 2
(-4750 2975);
FORCEPROP 1 LASTPIN (-4750 3075) $PN 1
J 2
(-4755 3037);
DISPLAY 0.617021 (-4755 3037);
PAINT WHITE (-4755 3037);
FORCEPROP 1 LASTPIN (-4750 2875) $PN 2
J 2
(-4755 2885);
DISPLAY 0.617021 (-4755 2885);
PAINT WHITE (-4755 2885);
FORCEPROP 1 LAST WATTAGE 1/16W
J 2
(-4790 2950);
DISPLAY 0.617021 (-4790 2950);
PAINT SKYBLUE (-4790 2950);
FORCEPROP 1 LAST MATERIAL CHIP
J 2
(-4790 2900);
DISPLAY 0.617021 (-4790 2900);
PAINT SKYBLUE (-4790 2900);
FORCEPROP 1 LAST PACK_TYPE 0402
J 2
(-4790 2800);
DISPLAY 0.617021 (-4790 2800);
PAINT SKYBLUE (-4790 2800);
FORCEPROP 1 LAST TOLERANCE 1%
J 2
(-4795 3000);
DISPLAY 0.617021 (-4795 3000);
PAINT SKYBLUE (-4795 3000);
FORCEPROP 1 LAST VALUE 475.0
J 2
(-4795 3050);
DISPLAY 0.617021 (-4795 3050);
PAINT SKYBLUE (-4795 3050);
FORCEPROP 1 LAST PART_NUMBER G21796-077
J 2
(-4790 2850);
DISPLAY 0.617021 (-4790 2850);
PAINT BLUE (-4790 2850);
FORCEPROP 1 LAST LOCATION R8F25
J 2
(-4795 3100);
DISPLAY 0.617021 (-4795 3100);
PAINT AQUA (-4795 3100);
FORCEPROP 2 LAST ROOM SYS_CLOCK
J 0
(-4775 3150);
DISPLAY 1.127660 (-4775 3150);
PAINT WHITE (-4775 3150);
DISPLAY INVISIBLE (-4775 3150);
FORCEPROP 1 LAST PATH I28
J 2
(-4800 3150);
DISPLAY 0.978723 (-4800 3150);
PAINT WHITE (-4800 3150);
DISPLAY INVISIBLE (-4800 3150);
FORCEPROP 2 LAST CDS_LOCATION R8F25
J 2
(-4795 3100);
DISPLAY 0.617021 (-4795 3100);
PAINT AQUA (-4795 3100);
DISPLAY INVISIBLE (-4795 3100);
FORCEPROP 2 LAST $SEC 1
J 0
(-4800 3200);
DISPLAY 1.510638 (-4800 3200);
PAINT MONO (-4800 3200);
DISPLAY INVISIBLE (-4800 3200);
FORCEPROP 2 LAST CDS_SEC 1
J 0
(-4800 3200);
DISPLAY 2.276596 (-4800 3200);
PAINT ORANGE (-4800 3200);
DISPLAY INVISIBLE (-4800 3200);
FORCEPROP 2 LAST BOM_COST SM_CONTROLLER
J 0
(-4775 3125);
DISPLAY 1.617021 (-4775 3125);
PAINT WHITE (-4775 3125);
DISPLAY INVISIBLE (-4775 3125);
FORCEPROP 2 LAST CDS_LIB mstr_discrete
J 0
(-4750 2975);
DISPLAY 1.617021 (-4750 2975);
PAINT MONO (-4750 2975);
DISPLAY INVISIBLE (-4750 2975);
FORCEADD GND..1
(-4750 2775);
FORCEPROP 3 LASTPIN (-4750 2825) SIG_NAME GND\g
J 0
(-4740 2835);
DISPLAY 0.659574 (-4740 2835);
PAINT MONO (-4740 2835);
DISPLAY INVISIBLE (-4740 2835);
FORCEPROP 1 LAST HDL_POWER GND
J 0
(-4750 2925);
PAINT GREEN (-4750 2925);
DISPLAY INVISIBLE (-4750 2925);
FORCEPROP 2 LAST ROOM SYS_CLOCK
J 0
(-5075 2850);
DISPLAY 1.127660 (-5075 2850);
PAINT WHITE (-5075 2850);
DISPLAY INVISIBLE (-5075 2850);
FORCEPROP 1 LAST PATH I29
J 0
(-4675 2775);
DISPLAY 0.872340 (-4675 2775);
PAINT AQUA (-4675 2775);
DISPLAY INVISIBLE (-4675 2775);
FORCEPROP 1 LAST BODY_TYPE PLUMBING
J 0
(-4795 2732);
DISPLAY 0.340426 (-4795 2732);
PAINT GREEN (-4795 2732);
DISPLAY INVISIBLE (-4795 2732);
FORCEPROP 2 LAST BOM_COST SM_CONTROLLER
J 0
(-5200 2850);
DISPLAY 1.617021 (-5200 2850);
PAINT WHITE (-5200 2850);
DISPLAY INVISIBLE (-5200 2850);
FORCEPROP 1 LAST SIZE 1B
J 0
(-4675 2725);
DISPLAY 1.127660 (-4675 2725);
PAINT ORANGE (-4675 2725);
DISPLAY INVISIBLE (-4675 2725);
FORCEPROP 2 LAST CDS_LIB mstr_symbols
J 0
(-4750 2775);
DISPLAY 1.617021 (-4750 2775);
PAINT MONO (-4750 2775);
DISPLAY INVISIBLE (-4750 2775);
FORCEPROP 1 LAST VOLTAGE 0.0V
J 0
(-4795 2732);
DISPLAY 0.340426 (-4795 2732);
PAINT SKYBLUE (-4795 2732);
DISPLAY INVISIBLE (-4795 2732);
FORCEADD GND..1
(-5025 775);
FORCEPROP 3 LASTPIN (-5025 825) SIG_NAME GND\g
J 0
(-5015 835);
DISPLAY 0.659574 (-5015 835);
PAINT MONO (-5015 835);
DISPLAY INVISIBLE (-5015 835);
FORCEPROP 1 LAST HDL_POWER GND
J 0
(-5025 925);
PAINT GREEN (-5025 925);
DISPLAY INVISIBLE (-5025 925);
FORCEPROP 2 LAST ROOM SYS_CLOCK
J 0
(-5350 850);
DISPLAY 1.127660 (-5350 850);
PAINT WHITE (-5350 850);
DISPLAY INVISIBLE (-5350 850);
FORCEPROP 1 LAST PATH I33
J 0
(-4950 775);
DISPLAY 0.872340 (-4950 775);
PAINT AQUA (-4950 775);
DISPLAY INVISIBLE (-4950 775);
FORCEPROP 1 LAST BODY_TYPE PLUMBING
J 0
(-5070 732);
DISPLAY 0.340426 (-5070 732);
PAINT GREEN (-5070 732);
DISPLAY INVISIBLE (-5070 732);
FORCEPROP 1 LAST SIZE 1B
J 0
(-4950 725);
DISPLAY 1.127660 (-4950 725);
PAINT ORANGE (-4950 725);
DISPLAY INVISIBLE (-4950 725);
FORCEPROP 2 LAST CDS_LIB mstr_symbols
J 0
(-5025 775);
DISPLAY 1.617021 (-5025 775);
PAINT MONO (-5025 775);
DISPLAY INVISIBLE (-5025 775);
FORCEPROP 2 LAST BOM_COST SM_CONTROLLER
J 0
(-5475 850);
DISPLAY 1.617021 (-5475 850);
PAINT WHITE (-5475 850);
DISPLAY INVISIBLE (-5475 850);
FORCEPROP 1 LAST VOLTAGE 0.0V
J 0
(-5070 732);
DISPLAY 0.340426 (-5070 732);
PAINT SKYBLUE (-5070 732);
DISPLAY INVISIBLE (-5070 732);
FORCEADD ICS9FGP204..1
(-5875 1825);
FORCEPROP 2 LASTPIN (-5225 2425) $PN 16
J 0
(-5215 2435);
DISPLAY 0.617021 (-5215 2435);
PAINT ORANGE (-5215 2435);
FORCEPROP 2 LASTPIN (-5225 2475) $PN 17
J 0
(-5215 2485);
DISPLAY 0.617021 (-5215 2485);
PAINT ORANGE (-5215 2485);
FORCEPROP 2 LASTPIN (-5225 2575) $PN 13
J 0
(-5215 2585);
DISPLAY 0.617021 (-5215 2585);
PAINT ORANGE (-5215 2585);
FORCEPROP 2 LASTPIN (-6525 1575) $PN 22
J 2
(-6535 1585);
DISPLAY 0.617021 (-6535 1585);
PAINT ORANGE (-6535 1585);
FORCEPROP 2 LASTPIN (-5225 1675) $PN 8
J 0
(-5215 1685);
DISPLAY 0.617021 (-5215 1685);
PAINT ORANGE (-5215 1685);
FORCEPROP 2 LASTPIN (-5225 1625) $PN 7
J 0
(-5215 1635);
DISPLAY 0.617021 (-5215 1635);
PAINT ORANGE (-5215 1635);
FORCEPROP 2 LASTPIN (-5225 1825) $PN 4
J 0
(-5215 1835);
DISPLAY 0.617021 (-5215 1835);
PAINT ORANGE (-5215 1835);
FORCEPROP 2 LASTPIN (-5225 1775) $PN 3
J 0
(-5215 1785);
DISPLAY 0.617021 (-5215 1785);
PAINT ORANGE (-5215 1785);
FORCEPROP 2 LASTPIN (-5225 1225) $PN 1
J 0
(-5215 1235);
DISPLAY 0.617021 (-5215 1235);
PAINT ORANGE (-5215 1235);
FORCEPROP 2 LASTPIN (-5225 1275) $PN 41
J 0
(-5215 1285);
DISPLAY 0.617021 (-5215 1285);
PAINT ORANGE (-5215 1285);
FORCEPROP 2 LASTPIN (-5225 1025) $PN 14
J 0
(-5215 1035);
DISPLAY 0.617021 (-5215 1035);
PAINT ORANGE (-5215 1035);
FORCEPROP 2 LASTPIN (-5225 1175) $PN 21
J 0
(-5215 1185);
DISPLAY 0.617021 (-5215 1185);
PAINT ORANGE (-5215 1185);
FORCEPROP 2 LASTPIN (-5225 1525) $PN 35
J 0
(-5215 1535);
DISPLAY 0.617021 (-5215 1535);
PAINT ORANGE (-5215 1535);
FORCEPROP 2 LASTPIN (-5225 975) $PN 10
J 0
(-5215 985);
DISPLAY 0.617021 (-5215 985);
PAINT ORANGE (-5215 985);
FORCEPROP 2 LASTPIN (-5225 1075) $PN 18
J 0
(-5215 1085);
DISPLAY 0.617021 (-5215 1085);
PAINT ORANGE (-5215 1085);
FORCEPROP 2 LASTPIN (-5225 1375) $PN 27
J 0
(-5215 1385);
DISPLAY 0.617021 (-5215 1385);
PAINT ORANGE (-5215 1385);
FORCEPROP 2 LASTPIN (-5225 1425) $PN 30
J 0
(-5215 1435);
DISPLAY 0.617021 (-5215 1435);
PAINT ORANGE (-5215 1435);
FORCEPROP 2 LASTPIN (-5225 2625) $PN 11
J 0
(-5215 2635);
DISPLAY 0.617021 (-5215 2635);
PAINT ORANGE (-5215 2635);
FORCEPROP 2 LASTPIN (-6525 1425) $PN 5
J 2
(-6535 1435);
DISPLAY 0.617021 (-6535 1435);
PAINT ORANGE (-6535 1435);
FORCEPROP 2 LASTPIN (-6525 1375) $PN 6
J 2
(-6535 1385);
DISPLAY 0.617021 (-6535 1385);
PAINT ORANGE (-6535 1385);
FORCEPROP 2 LASTPIN (-5225 1925) $PN 37
J 0
(-5215 1935);
DISPLAY 0.617021 (-5215 1935);
PAINT ORANGE (-5215 1935);
FORCEPROP 2 LASTPIN (-5225 1975) $PN 36
J 0
(-5215 1985);
DISPLAY 0.617021 (-5215 1985);
PAINT ORANGE (-5215 1985);
FORCEPROP 2 LASTPIN (-5225 2075) $PN 33
J 0
(-5215 2085);
DISPLAY 0.617021 (-5215 2085);
PAINT ORANGE (-5215 2085);
FORCEPROP 2 LASTPIN (-5225 2125) $PN 32
J 0
(-5215 2135);
DISPLAY 0.617021 (-5215 2135);
PAINT ORANGE (-5215 2135);
FORCEPROP 2 LASTPIN (-5225 2175) $PN 29
J 0
(-5215 2185);
DISPLAY 0.617021 (-5215 2185);
PAINT ORANGE (-5215 2185);
FORCEPROP 2 LASTPIN (-5225 2225) $PN 28
J 0
(-5215 2235);
DISPLAY 0.617021 (-5215 2235);
PAINT ORANGE (-5215 2235);
FORCEPROP 2 LASTPIN (-5225 2275) $PN 25
J 0
(-5215 2285);
DISPLAY 0.617021 (-5215 2285);
PAINT ORANGE (-5215 2285);
FORCEPROP 2 LASTPIN (-5225 2325) $PN 24
J 0
(-5215 2335);
DISPLAY 0.617021 (-5215 2335);
PAINT ORANGE (-5215 2335);
FORCEPROP 2 LASTPIN (-6525 1925) $PN 38
J 2
(-6535 1935);
DISPLAY 0.617021 (-6535 1935);
PAINT ORANGE (-6535 1935);
FORCEPROP 2 LASTPIN (-6525 1875) $PN 39
J 2
(-6535 1885);
DISPLAY 0.617021 (-6535 1885);
PAINT ORANGE (-6535 1885);
FORCEPROP 2 LASTPIN (-6525 2075) $PN 12
J 2
(-6535 2085);
DISPLAY 0.617021 (-6535 2085);
PAINT ORANGE (-6535 2085);
FORCEPROP 2 LASTPIN (-6525 2225) $PN 23
J 2
(-6535 2235);
DISPLAY 0.617021 (-6535 2235);
PAINT ORANGE (-6535 2235);
FORCEPROP 2 LASTPIN (-6525 2275) $PN 2
J 2
(-6535 2285);
DISPLAY 0.617021 (-6535 2285);
PAINT ORANGE (-6535 2285);
FORCEPROP 2 LASTPIN (-6525 2525) $PN 34
J 2
(-6535 2535);
DISPLAY 0.617021 (-6535 2535);
PAINT ORANGE (-6535 2535);
FORCEPROP 2 LASTPIN (-6525 2025) $PN 9
J 2
(-6535 2035);
DISPLAY 0.617021 (-6535 2035);
PAINT ORANGE (-6535 2035);
FORCEPROP 2 LASTPIN (-6525 2125) $PN 15
J 2
(-6535 2135);
DISPLAY 0.617021 (-6535 2135);
PAINT ORANGE (-6535 2135);
FORCEPROP 2 LASTPIN (-6525 2375) $PN 26
J 2
(-6535 2385);
DISPLAY 0.617021 (-6535 2385);
PAINT ORANGE (-6535 2385);
FORCEPROP 2 LASTPIN (-6525 2425) $PN 31
J 2
(-6535 2435);
DISPLAY 0.617021 (-6535 2435);
PAINT ORANGE (-6535 2435);
FORCEPROP 2 LASTPIN (-6525 1075) $PN 40
J 2
(-6535 1085);
DISPLAY 0.617021 (-6535 1085);
PAINT ORANGE (-6535 1085);
FORCEPROP 2 LASTPIN (-6525 1175) $PN 19
J 2
(-6535 1185);
DISPLAY 0.617021 (-6535 1185);
PAINT ORANGE (-6535 1185);
FORCEPROP 2 LASTPIN (-6525 1225) $PN 20
J 2
(-6535 1235);
DISPLAY 0.617021 (-6535 1235);
PAINT ORANGE (-6535 1235);
FORCEPROP 1 LAST MATERIAL IC
J 0
(-6475 2775);
DISPLAY 0.617021 (-6475 2775);
PAINT SKYBLUE (-6475 2775);
FORCEPROP 1 LAST PART_NUMBER E95226-001
J 0
(-6475 875);
DISPLAY 0.617021 (-6475 875);
PAINT BLUE (-6475 875);
FORCEPROP 1 LAST LOCATION EU8F2
J 0
(-6475 2825);
DISPLAY 0.617021 (-6475 2825);
PAINT AQUA (-6475 2825);
FORCEPROP 2 LAST ROOM SYS_CLOCK
J 0
(-6475 2875);
DISPLAY 2.276596 (-6475 2875);
PAINT WHITE (-6475 2875);
DISPLAY INVISIBLE (-6475 2875);
FORCEPROP 1 LAST PATH I34
J 0
(-5875 2775);
PAINT GREEN (-5875 2775);
DISPLAY INVISIBLE (-5875 2775);
FORCEPROP 2 LAST CDS_LOCATION EU8F2
J 0
(-6475 2825);
DISPLAY 0.617021 (-6475 2825);
PAINT AQUA (-6475 2825);
DISPLAY INVISIBLE (-6475 2825);
FORCEPROP 2 LAST SEC 1
J 0
(-6475 2875);
DISPLAY 0.680851 (-6475 2875);
PAINT MONO (-6475 2875);
DISPLAY INVISIBLE (-6475 2875);
FORCEPROP 2 LAST SEC_TYPE MLFP
J 0
(-6475 2875);
DISPLAY 1.021277 (-6475 2875);
PAINT ORANGE (-6475 2875);
DISPLAY INVISIBLE (-6475 2875);
FORCEPROP 1 LAST CDS_LMAN_SYM_OUTLINE -600,900,600,-900
J 0
(-5875 1825);
PAINT GREEN (-5875 1825);
DISPLAY INVISIBLE (-5875 1825);
FORCEPROP 2 LAST CDS_LIB mstr_clock
J 0
(-5875 1825);
DISPLAY 1.617021 (-5875 1825);
PAINT MONO (-5875 1825);
DISPLAY INVISIBLE (-5875 1825);
FORCEPROP 2 LAST BOM_COST SM_CONTROLLER
J 0
(-6475 2875);
DISPLAY 1.617021 (-6475 2875);
PAINT WHITE (-6475 2875);
DISPLAY INVISIBLE (-6475 2875);
FORCEPROP 1 LAST PACK_TYPE MLFP
J 0
(-6475 2875);
DISPLAY 1.617021 (-6475 2875);
PAINT SKYBLUE (-6475 2875);
DISPLAY INVISIBLE (-6475 2875);
FORCEADD RES..2
(-8300 1200);
FORCEPROP 1 LASTPIN (-8300 1300) $PN 1
J 0
(-8295 1262);
DISPLAY 0.617021 (-8295 1262);
PAINT ORANGE (-8295 1262);
FORCEPROP 1 LASTPIN (-8300 1100) $PN 2
J 0
(-8295 1110);
DISPLAY 0.617021 (-8295 1110);
PAINT ORANGE (-8295 1110);
FORCEPROP 1 LAST WATTAGE 1/16W
J 0
(-8260 1175);
DISPLAY 0.617021 (-8260 1175);
PAINT SKYBLUE (-8260 1175);
FORCEPROP 1 LAST MATERIAL CHIP
J 0
(-8260 1125);
DISPLAY 0.617021 (-8260 1125);
PAINT SKYBLUE (-8260 1125);
FORCEPROP 1 LAST PACK_TYPE 0402
J 0
(-8260 1025);
DISPLAY 0.617021 (-8260 1025);
PAINT SKYBLUE (-8260 1025);
FORCEPROP 1 LAST TOLERANCE 1%
J 0
(-8255 1225);
DISPLAY 0.617021 (-8255 1225);
PAINT SKYBLUE (-8255 1225);
FORCEPROP 1 LAST VALUE 1.00K
J 0
(-8255 1275);
DISPLAY 0.617021 (-8255 1275);
PAINT SKYBLUE (-8255 1275);
FORCEPROP 1 LAST PART_NUMBER G21796-026
J 0
(-8260 1075);
DISPLAY 0.617021 (-8260 1075);
PAINT BLUE (-8260 1075);
FORCEPROP 1 LAST LOCATION R2T25
J 0
(-8255 1325);
DISPLAY 0.617021 (-8255 1325);
PAINT AQUA (-8255 1325);
FORCEPROP 2 LAST ROOM SYS_CLOCK
J 2
(-8275 1375);
DISPLAY 1.127660 (-8275 1375);
PAINT WHITE (-8275 1375);
DISPLAY INVISIBLE (-8275 1375);
FORCEPROP 1 LAST PATH I48
J 0
(-8250 1375);
DISPLAY 0.978723 (-8250 1375);
PAINT WHITE (-8250 1375);
DISPLAY INVISIBLE (-8250 1375);
FORCEPROP 2 LAST CDS_LOCATION R2T25
J 0
(-8255 1325);
DISPLAY 0.617021 (-8255 1325);
PAINT AQUA (-8255 1325);
DISPLAY INVISIBLE (-8255 1325);
FORCEPROP 2 LAST SEC 1
J 0
(-8250 1425);
DISPLAY 0.680851 (-8250 1425);
PAINT MONO (-8250 1425);
DISPLAY INVISIBLE (-8250 1425);
FORCEPROP 2 LAST SEC_TYPE 0402
J 0
(-8250 1425);
DISPLAY 1.021277 (-8250 1425);
PAINT ORANGE (-8250 1425);
DISPLAY INVISIBLE (-8250 1425);
FORCEPROP 2 LAST BOM_COST SM_CONTROLLER
J 2
(-8275 1350);
DISPLAY 1.617021 (-8275 1350);
PAINT WHITE (-8275 1350);
DISPLAY INVISIBLE (-8275 1350);
FORCEPROP 2 LAST CDS_LIB mstr_discrete
J 2
(-8300 1200);
DISPLAY 1.617021 (-8300 1200);
PAINT MONO (-8300 1200);
DISPLAY INVISIBLE (-8300 1200);
FORCEADD CAP..1
(-7275 775);
FORCEPROP 1 LASTPIN (-7275 875) $PN 1
J 0
(-7265 855);
DISPLAY 0.617021 (-7265 855);
PAINT WHITE (-7265 855);
FORCEPROP 1 LASTPIN (-7275 675) $PN 2
J 0
(-7265 655);
DISPLAY 0.617021 (-7265 655);
PAINT WHITE (-7265 655);
FORCEPROP 1 LAST MATERIAL COG
J 0
(-7225 675);
DISPLAY 0.617021 (-7225 675);
PAINT SKYBLUE (-7225 675);
FORCEPROP 1 LAST VOLTAGE 50V
J 0
(-7225 775);
DISPLAY 0.617021 (-7225 775);
PAINT SKYBLUE (-7225 775);
FORCEPROP 1 LAST PACK_TYPE 0402LF
J 0
(-7225 575);
DISPLAY 0.617021 (-7225 575);
PAINT SKYBLUE (-7225 575);
FORCEPROP 1 LAST TOLERANCE 5%
J 0
(-7225 725);
DISPLAY 0.617021 (-7225 725);
PAINT SKYBLUE (-7225 725);
FORCEPROP 1 LAST VALUE 27.0PF
J 0
(-7225 825);
DISPLAY 0.617021 (-7225 825);
PAINT SKYBLUE (-7225 825);
FORCEPROP 1 LAST PART_NUMBER A36095-038
J 0
(-7225 625);
DISPLAY 0.617021 (-7225 625);
PAINT BLUE (-7225 625);
FORCEPROP 1 LAST LOCATION C8F18
J 0
(-7225 875);
DISPLAY 0.617021 (-7225 875);
PAINT AQUA (-7225 875);
FORCEPROP 2 LAST ROOM SYS_CLOCK
J 0
(-7225 925);
DISPLAY 1.127660 (-7225 925);
PAINT WHITE (-7225 925);
DISPLAY INVISIBLE (-7225 925);
FORCEPROP 1 LAST PATH I49
J 0
(-7225 925);
DISPLAY 0.978723 (-7225 925);
PAINT WHITE (-7225 925);
DISPLAY INVISIBLE (-7225 925);
FORCEPROP 2 LAST CDS_LOCATION C8F18
J 0
(-7225 875);
DISPLAY 0.617021 (-7225 875);
PAINT AQUA (-7225 875);
DISPLAY INVISIBLE (-7225 875);
FORCEPROP 2 LAST $SEC 1
J 0
(-7225 975);
DISPLAY 1.510638 (-7225 975);
PAINT MONO (-7225 975);
DISPLAY INVISIBLE (-7225 975);
FORCEPROP 2 LAST CDS_SEC 1
J 0
(-7225 1000);
DISPLAY 1.659574 (-7225 1000);
PAINT ORANGE (-7225 1000);
DISPLAY INVISIBLE (-7225 1000);
FORCEPROP 2 LAST BOM_COST SM_CONTROLLER
J 0
(-7225 900);
DISPLAY 1.617021 (-7225 900);
PAINT WHITE (-7225 900);
DISPLAY INVISIBLE (-7225 900);
FORCEPROP 2 LAST CDS_LIB mstr_discrete
J 0
(-7275 775);
DISPLAY 1.617021 (-7275 775);
PAINT MONO (-7275 775);
DISPLAY INVISIBLE (-7275 775);
FORCEADD CRYSTAL..3
R 2
(-7450 1000);
FORCEPROP 1 LASTPIN (-7350 1000) $PN 1
J 0
(-7395 1010);
DISPLAY 0.617021 (-7395 1010);
PAINT WHITE (-7395 1010);
FORCEPROP 1 LASTPIN (-7550 1000) $PN 3
J 2
(-7515 1010);
DISPLAY 0.617021 (-7515 1010);
PAINT WHITE (-7515 1010);
FORCEPROP 1 LAST MATERIAL IC
J 2
(-7439 916);
DISPLAY 0.617021 (-7439 916);
PAINT SKYBLUE (-7439 916);
FORCEPROP 1 LAST VALUE 25.000MHZ
J 1
(-7457 1061);
DISPLAY 0.617021 (-7457 1061);
PAINT SKYBLUE (-7457 1061);
FORCEPROP 1 LAST PART_NUMBER D71700-033
J 2
(-7350 1150);
DISPLAY 0.617021 (-7350 1150);
PAINT BLUE (-7350 1150);
FORCEPROP 1 LAST LOCATION Y8F1
J 1
(-7455 1099);
DISPLAY 0.617021 (-7455 1099);
PAINT AQUA (-7455 1099);
FORCEPROP 1 LAST POWER_GROUP GND=GND
J 2
(-7300 850);
DISPLAY 0.617021 (-7300 850);
PAINT ORANGE (-7300 850);
FORCEPROP 2 LAST ROOM SYS_CLOCK
J 2
(-7475 1200);
DISPLAY 2.276596 (-7475 1200);
PAINT WHITE (-7475 1200);
DISPLAY INVISIBLE (-7475 1200);
FORCEPROP 1 LAST PATH I52
J 2
(-7475 1100);
DISPLAY 0.872340 (-7475 1100);
PAINT PINK (-7475 1100);
DISPLAY INVISIBLE (-7475 1100);
FORCEPROP 2 LAST CDS_LOCATION Y8F1
J 1
(-7455 1099);
DISPLAY 0.617021 (-7455 1099);
PAINT AQUA (-7455 1099);
DISPLAY INVISIBLE (-7455 1099);
FORCEPROP 2 LAST $SEC 1
J 2
(-7475 1150);
DISPLAY 1.510638 (-7475 1150);
PAINT MONO (-7475 1150);
DISPLAY INVISIBLE (-7475 1150);
FORCEPROP 2 LAST CDS_SEC 1
J 2
(-7475 1150);
DISPLAY 2.276596 (-7475 1150);
PAINT ORANGE (-7475 1150);
DISPLAY INVISIBLE (-7475 1150);
FORCEPROP 2 LAST CDS_LIB mstr_discrete
J 2
(-7450 1000);
DISPLAY 1.617021 (-7450 1000);
PAINT ORANGE (-7450 1000);
DISPLAY INVISIBLE (-7450 1000);
FORCEPROP 0 LAST BOM_COST SM_CONTROLLER
J 0
(-7350 1250);
DISPLAY 1.021277 (-7350 1250);
PAINT ORANGE (-7350 1250);
DISPLAY INVISIBLE (-7350 1250);
FORCEPROP 1 LAST PACK_TYPE 2013LF
J 2
(-7438 908);
DISPLAY 1.617021 (-7438 908);
PAINT SKYBLUE (-7438 908);
DISPLAY INVISIBLE (-7438 908);
FORCEADD CAP..1
R 2
(-7625 775);
FORCEPROP 1 LASTPIN (-7625 875) $PN 1
J 2
(-7635 855);
DISPLAY 0.617021 (-7635 855);
PAINT WHITE (-7635 855);
FORCEPROP 1 LASTPIN (-7625 675) $PN 2
J 2
(-7635 655);
DISPLAY 0.617021 (-7635 655);
PAINT WHITE (-7635 655);
FORCEPROP 1 LAST MATERIAL COG
J 2
(-7675 675);
DISPLAY 0.617021 (-7675 675);
PAINT SKYBLUE (-7675 675);
FORCEPROP 1 LAST VOLTAGE 50V
J 2
(-7675 775);
DISPLAY 0.617021 (-7675 775);
PAINT SKYBLUE (-7675 775);
FORCEPROP 1 LAST PACK_TYPE 0402LF
J 2
(-7675 575);
DISPLAY 0.617021 (-7675 575);
PAINT SKYBLUE (-7675 575);
FORCEPROP 1 LAST TOLERANCE 5%
J 2
(-7675 725);
DISPLAY 0.617021 (-7675 725);
PAINT SKYBLUE (-7675 725);
FORCEPROP 1 LAST VALUE 27.0PF
J 2
(-7675 825);
DISPLAY 0.617021 (-7675 825);
PAINT SKYBLUE (-7675 825);
FORCEPROP 1 LAST PART_NUMBER A36095-038
J 2
(-7675 625);
DISPLAY 0.617021 (-7675 625);
PAINT BLUE (-7675 625);
FORCEPROP 1 LAST LOCATION C8F19
J 2
(-7675 875);
DISPLAY 0.617021 (-7675 875);
PAINT AQUA (-7675 875);
FORCEPROP 2 LAST ROOM SYS_CLOCK
J 0
(-7675 925);
DISPLAY 1.127660 (-7675 925);
PAINT WHITE (-7675 925);
DISPLAY INVISIBLE (-7675 925);
FORCEPROP 1 LAST PATH I53
J 2
(-7675 925);
DISPLAY 0.978723 (-7675 925);
PAINT WHITE (-7675 925);
DISPLAY INVISIBLE (-7675 925);
FORCEPROP 2 LAST CDS_LOCATION C8F19
J 2
(-7675 875);
DISPLAY 0.617021 (-7675 875);
PAINT AQUA (-7675 875);
DISPLAY INVISIBLE (-7675 875);
FORCEPROP 2 LAST $SEC 1
J 0
(-7675 975);
DISPLAY 1.510638 (-7675 975);
PAINT MONO (-7675 975);
DISPLAY INVISIBLE (-7675 975);
FORCEPROP 2 LAST CDS_SEC 1
J 0
(-7675 1000);
DISPLAY 1.659574 (-7675 1000);
PAINT ORANGE (-7675 1000);
DISPLAY INVISIBLE (-7675 1000);
FORCEPROP 2 LAST BOM_COST SM_CONTROLLER
J 0
(-7675 900);
DISPLAY 1.617021 (-7675 900);
PAINT WHITE (-7675 900);
DISPLAY INVISIBLE (-7675 900);
FORCEPROP 2 LAST CDS_LIB mstr_discrete
J 0
(-7625 775);
DISPLAY 1.617021 (-7625 775);
PAINT MONO (-7625 775);
DISPLAY INVISIBLE (-7625 775);
FORCEADD GND..1
(-7450 475);
FORCEPROP 3 LASTPIN (-7450 525) SIG_NAME GND\g
J 0
(-7440 535);
DISPLAY 0.659574 (-7440 535);
PAINT MONO (-7440 535);
DISPLAY INVISIBLE (-7440 535);
FORCEPROP 1 LAST HDL_POWER GND
J 0
(-7450 625);
PAINT GREEN (-7450 625);
DISPLAY INVISIBLE (-7450 625);
FORCEPROP 2 LAST ROOM SYS_CLOCK
J 0
(-7775 550);
DISPLAY 1.127660 (-7775 550);
PAINT WHITE (-7775 550);
DISPLAY INVISIBLE (-7775 550);
FORCEPROP 1 LAST PATH I54
J 0
(-7375 475);
DISPLAY 0.872340 (-7375 475);
PAINT AQUA (-7375 475);
DISPLAY INVISIBLE (-7375 475);
FORCEPROP 1 LAST BODY_TYPE PLUMBING
J 0
(-7495 432);
DISPLAY 0.340426 (-7495 432);
PAINT GREEN (-7495 432);
DISPLAY INVISIBLE (-7495 432);
FORCEPROP 2 LAST BOM_COST SM_CONTROLLER
J 0
(-7900 550);
DISPLAY 1.617021 (-7900 550);
PAINT WHITE (-7900 550);
DISPLAY INVISIBLE (-7900 550);
FORCEPROP 1 LAST SIZE 1B
J 0
(-7375 425);
DISPLAY 1.127660 (-7375 425);
PAINT ORANGE (-7375 425);
DISPLAY INVISIBLE (-7375 425);
FORCEPROP 2 LAST CDS_LIB mstr_symbols
J 0
(-7450 475);
DISPLAY 1.617021 (-7450 475);
PAINT MONO (-7450 475);
DISPLAY INVISIBLE (-7450 475);
FORCEPROP 1 LAST VOLTAGE 0.0V
J 0
(-7495 432);
DISPLAY 0.340426 (-7495 432);
PAINT SKYBLUE (-7495 432);
DISPLAY INVISIBLE (-7495 432);
FORCEADD OFFPAGE..1
(-7800 200);
FORCEPROP 2 LAST $XR0 240 
J 0
(-8052 200);
DISPLAY 0.638298 (-8052 200);
PAINT MONO (-8052 200);
FORCEPROP 2 LAST $XR1 189 
J 0
(-8172 200);
DISPLAY 0.638298 (-8172 200);
PAINT MONO (-8172 200);
FORCEPROP 2 LAST $XR2 191 
J 0
(-8292 200);
DISPLAY 0.638298 (-8292 200);
PAINT MONO (-8292 200);
FORCEPROP 2 LAST $XR3 196 
J 0
(-8412 200);
DISPLAY 0.638298 (-8412 200);
PAINT MONO (-8412 200);
FORCEPROP 2 LAST $XR4 237 
J 0
(-8532 200);
DISPLAY 0.638298 (-8532 200);
PAINT MONO (-8532 200);
FORCEPROP 2 LAST $XR5 239 
J 0
(-8652 200);
DISPLAY 0.638298 (-8652 200);
PAINT MONO (-8652 200);
FORCEPROP 2 LAST PATH I55
J 0
(-8050 250);
DISPLAY 1.021277 (-8050 250);
PAINT ORANGE (-8050 250);
DISPLAY INVISIBLE (-8050 250);
FORCEPROP 1 LAST COMMENT_BODY TRUE
J 0
(-7675 100);
DISPLAY 1.404255 (-7675 100);
PAINT PEACH (-7675 100);
DISPLAY INVISIBLE (-7675 100);
FORCEPROP 1 LAST OFFPAGE TRUE
J 0
(-7475 75);
PAINT GREEN (-7475 75);
DISPLAY INVISIBLE (-7475 75);
FORCEPROP 2 LAST CDS_LIB mstr_standard
J 0
(-7800 200);
DISPLAY 1.617021 (-7800 200);
PAINT MONO (-7800 200);
DISPLAY INVISIBLE (-7800 200);
FORCEADD GND..1
(-8475 3650);
FORCEPROP 3 LASTPIN (-8475 3700) SIG_NAME GND\g
J 0
(-8465 3710);
DISPLAY 0.659574 (-8465 3710);
PAINT MONO (-8465 3710);
DISPLAY INVISIBLE (-8465 3710);
FORCEPROP 1 LAST HDL_POWER GND
J 0
(-8475 3800);
PAINT GREEN (-8475 3800);
DISPLAY INVISIBLE (-8475 3800);
FORCEPROP 2 LAST ROOM SYS_CLOCK
J 0
(-8800 3725);
DISPLAY 1.127660 (-8800 3725);
PAINT WHITE (-8800 3725);
DISPLAY INVISIBLE (-8800 3725);
FORCEPROP 1 LAST PATH I58
J 0
(-8400 3650);
DISPLAY 0.872340 (-8400 3650);
PAINT AQUA (-8400 3650);
DISPLAY INVISIBLE (-8400 3650);
FORCEPROP 1 LAST BODY_TYPE PLUMBING
J 0
(-8520 3607);
DISPLAY 0.340426 (-8520 3607);
PAINT GREEN (-8520 3607);
DISPLAY INVISIBLE (-8520 3607);
FORCEPROP 1 LAST SIZE 1B
J 0
(-8400 3600);
DISPLAY 1.127660 (-8400 3600);
PAINT GREEN (-8400 3600);
DISPLAY INVISIBLE (-8400 3600);
FORCEPROP 2 LAST CDS_LIB mstr_symbols
J 0
(-8475 3650);
DISPLAY 2.127660 (-8475 3650);
PAINT ORANGE (-8475 3650);
DISPLAY INVISIBLE (-8475 3650);
FORCEPROP 2 LAST BOM_COST SM_CONTROLLER
J 0
(-8925 3725);
DISPLAY 1.617021 (-8925 3725);
PAINT WHITE (-8925 3725);
DISPLAY INVISIBLE (-8925 3725);
FORCEPROP 1 LAST VOLTAGE 0.0V
J 0
(-8520 3607);
DISPLAY 0.340426 (-8520 3607);
PAINT SKYBLUE (-8520 3607);
DISPLAY INVISIBLE (-8520 3607);
FORCEADD OFFPAGE..3
R 2
(-7200 1875);
FORCEPROP 2 LAST $XR0 102 
J 0
(-7510 1875);
DISPLAY 0.638298 (-7510 1875);
PAINT MONO (-7510 1875);
FORCEPROP 2 LAST $XR1 111 
J 0
(-7630 1875);
DISPLAY 0.638298 (-7630 1875);
PAINT MONO (-7630 1875);
FORCEPROP 2 LAST $XR2 138 
J 0
(-7750 1875);
DISPLAY 0.638298 (-7750 1875);
PAINT MONO (-7750 1875);
FORCEPROP 2 LAST $XR3 156 
J 0
(-7870 1875);
DISPLAY 0.638298 (-7870 1875);
PAINT MONO (-7870 1875);
FORCEPROP 2 LAST $XR4 159 
J 0
(-7990 1875);
DISPLAY 0.638298 (-7990 1875);
PAINT MONO (-7990 1875);
FORCEPROP 2 LAST $XR5 247 
J 0
(-7990 1875);
DISPLAY 0.638298 (-7990 1875);
PAINT MONO (-7990 1875);
FORCEPROP 2 LAST PATH I59
J 2
(-7250 1950);
DISPLAY 1.021277 (-7250 1950);
PAINT ORANGE (-7250 1950);
DISPLAY INVISIBLE (-7250 1950);
FORCEPROP 1 LAST COMMENT_BODY TRUE
J 2
(-7150 1775);
DISPLAY 0.872340 (-7150 1775);
PAINT GREEN (-7150 1775);
DISPLAY INVISIBLE (-7150 1775);
FORCEPROP 1 LAST OFFPAGE TRUE
J 2
(-7525 1750);
DISPLAY 0.872340 (-7525 1750);
PAINT GREEN (-7525 1750);
DISPLAY INVISIBLE (-7525 1750);
FORCEPROP 2 LAST CDS_LIB mstr_standard
J 2
(-7200 1875);
DISPLAY 1.617021 (-7200 1875);
PAINT MONO (-7200 1875);
DISPLAY INVISIBLE (-7200 1875);
FORCEADD OFFPAGE..1
(-7200 1925);
FORCEPROP 2 LAST $XR0 138 
J 0
(-7452 1925);
DISPLAY 0.638298 (-7452 1925);
PAINT MONO (-7452 1925);
FORCEPROP 2 LAST $XR1 159 
J 0
(-7572 1925);
DISPLAY 0.638298 (-7572 1925);
PAINT MONO (-7572 1925);
FORCEPROP 2 LAST $XR2 102 
J 0
(-7692 1925);
DISPLAY 0.638298 (-7692 1925);
PAINT MONO (-7692 1925);
FORCEPROP 2 LAST $XR3 111 
J 0
(-7812 1925);
DISPLAY 0.638298 (-7812 1925);
PAINT MONO (-7812 1925);
FORCEPROP 2 LAST $XR4 156 
J 0
(-7932 1925);
DISPLAY 0.638298 (-7932 1925);
PAINT MONO (-7932 1925);
FORCEPROP 2 LAST $XR5 247 
J 0
(-7932 1925);
DISPLAY 0.638298 (-7932 1925);
PAINT MONO (-7932 1925);
FORCEPROP 2 LAST PATH I60
J 0
(-7150 2000);
DISPLAY 1.021277 (-7150 2000);
PAINT ORANGE (-7150 2000);
DISPLAY INVISIBLE (-7150 2000);
FORCEPROP 1 LAST COMMENT_BODY TRUE
J 0
(-7075 1825);
DISPLAY 1.404255 (-7075 1825);
PAINT PEACH (-7075 1825);
DISPLAY INVISIBLE (-7075 1825);
FORCEPROP 1 LAST OFFPAGE TRUE
J 0
(-6875 1800);
PAINT GREEN (-6875 1800);
DISPLAY INVISIBLE (-6875 1800);
FORCEPROP 2 LAST CDS_LIB mstr_standard
J 0
(-7200 1925);
DISPLAY 1.617021 (-7200 1925);
PAINT MONO (-7200 1925);
DISPLAY INVISIBLE (-7200 1925);
FORCEADD GND..1
(-8300 875);
FORCEPROP 3 LASTPIN (-8300 925) SIG_NAME GND\g
J 0
(-8290 935);
DISPLAY 0.659574 (-8290 935);
PAINT MONO (-8290 935);
DISPLAY INVISIBLE (-8290 935);
FORCEPROP 1 LAST HDL_POWER GND
J 0
(-8300 1025);
PAINT GREEN (-8300 1025);
DISPLAY INVISIBLE (-8300 1025);
FORCEPROP 2 LAST ROOM SYS_CLOCK
J 0
(-8625 950);
DISPLAY 1.127660 (-8625 950);
PAINT WHITE (-8625 950);
DISPLAY INVISIBLE (-8625 950);
FORCEPROP 1 LAST PATH I64
J 0
(-8225 875);
DISPLAY 0.872340 (-8225 875);
PAINT AQUA (-8225 875);
DISPLAY INVISIBLE (-8225 875);
FORCEPROP 1 LAST BODY_TYPE PLUMBING
J 0
(-8345 832);
DISPLAY 0.340426 (-8345 832);
PAINT GREEN (-8345 832);
DISPLAY INVISIBLE (-8345 832);
FORCEPROP 2 LAST BOM_COST SM_CONTROLLER
J 0
(-8750 950);
DISPLAY 1.617021 (-8750 950);
PAINT WHITE (-8750 950);
DISPLAY INVISIBLE (-8750 950);
FORCEPROP 1 LAST SIZE 1B
J 0
(-8225 825);
DISPLAY 1.127660 (-8225 825);
PAINT ORANGE (-8225 825);
DISPLAY INVISIBLE (-8225 825);
FORCEPROP 2 LAST CDS_LIB mstr_symbols
J 0
(-8300 875);
PAINT ORANGE (-8300 875);
DISPLAY INVISIBLE (-8300 875);
FORCEPROP 1 LAST VOLTAGE 0.0V
J 0
(-8345 832);
DISPLAY 0.340426 (-8345 832);
PAINT SKYBLUE (-8345 832);
DISPLAY INVISIBLE (-8345 832);
FORCEADD OFFPAGE..2
(-2250 1675);
FORCEPROP 2 LAST $XR0 147 
J 0
(-2061 1675);
DISPLAY 0.638298 (-2061 1675);
PAINT MONO (-2061 1675);
FORCEPROP 2 LAST PATH I71
J 0
(-2200 1750);
DISPLAY 1.021277 (-2200 1750);
PAINT ORANGE (-2200 1750);
DISPLAY INVISIBLE (-2200 1750);
FORCEPROP 1 LAST COMMENT_BODY TRUE
J 0
(-2295 1580);
DISPLAY 0.872340 (-2295 1580);
PAINT GREEN (-2295 1580);
DISPLAY INVISIBLE (-2295 1580);
FORCEPROP 1 LAST OFFPAGE TRUE
J 0
(-1925 1550);
DISPLAY 0.872340 (-1925 1550);
PAINT GREEN (-1925 1550);
DISPLAY INVISIBLE (-1925 1550);
FORCEPROP 2 LAST CDS_LIB mstr_standard
J 0
(-2250 1675);
PAINT ORANGE (-2250 1675);
DISPLAY INVISIBLE (-2250 1675);
FORCEADD OFFPAGE..2
(-2250 1525);
FORCEPROP 2 LAST $XR0 186 
J 0
(-2061 1525);
DISPLAY 0.638298 (-2061 1525);
PAINT MONO (-2061 1525);
FORCEPROP 2 LAST PATH I72
J 0
(-2075 1600);
DISPLAY 1.021277 (-2075 1600);
PAINT ORANGE (-2075 1600);
DISPLAY INVISIBLE (-2075 1600);
FORCEPROP 1 LAST COMMENT_BODY TRUE
J 0
(-2295 1430);
DISPLAY 0.872340 (-2295 1430);
PAINT GREEN (-2295 1430);
DISPLAY INVISIBLE (-2295 1430);
FORCEPROP 1 LAST OFFPAGE TRUE
J 0
(-1925 1400);
DISPLAY 0.872340 (-1925 1400);
PAINT GREEN (-1925 1400);
DISPLAY INVISIBLE (-1925 1400);
FORCEPROP 2 LAST CDS_LIB mstr_standard
J 0
(-2250 1525);
PAINT ORANGE (-2250 1525);
DISPLAY INVISIBLE (-2250 1525);
FORCEADD OFFPAGE..2
(-2250 2125);
FORCEPROP 2 LAST $XR0 121 
J 0
(-2061 2125);
DISPLAY 0.638298 (-2061 2125);
PAINT MONO (-2061 2125);
FORCEPROP 2 LAST PATH I79
J 0
(-2050 2175);
DISPLAY 1.021277 (-2050 2175);
PAINT ORANGE (-2050 2175);
DISPLAY INVISIBLE (-2050 2175);
FORCEPROP 1 LAST COMMENT_BODY TRUE
J 0
(-2295 2030);
DISPLAY 1.404255 (-2295 2030);
PAINT PEACH (-2295 2030);
DISPLAY INVISIBLE (-2295 2030);
FORCEPROP 1 LAST OFFPAGE TRUE
J 0
(-1925 2000);
PAINT GREEN (-1925 2000);
DISPLAY INVISIBLE (-1925 2000);
FORCEPROP 2 LAST CDS_LIB mstr_standard
J 0
(-2250 2125);
DISPLAY 1.617021 (-2250 2125);
PAINT MONO (-2250 2125);
DISPLAY INVISIBLE (-2250 2125);
FORCEADD OFFPAGE..2
(-2250 1825);
FORCEPROP 2 LAST $XR0 147 
J 0
(-2061 1825);
DISPLAY 0.638298 (-2061 1825);
PAINT MONO (-2061 1825);
FORCEPROP 2 LAST PATH I80
J 0
(-2075 1900);
DISPLAY 1.021277 (-2075 1900);
PAINT ORANGE (-2075 1900);
DISPLAY INVISIBLE (-2075 1900);
FORCEPROP 1 LAST COMMENT_BODY TRUE
J 0
(-2295 1730);
DISPLAY 1.404255 (-2295 1730);
PAINT PEACH (-2295 1730);
DISPLAY INVISIBLE (-2295 1730);
FORCEPROP 1 LAST OFFPAGE TRUE
J 0
(-1925 1700);
PAINT GREEN (-1925 1700);
DISPLAY INVISIBLE (-1925 1700);
FORCEPROP 2 LAST CDS_LIB mstr_standard
J 0
(-2250 1825);
DISPLAY 1.617021 (-2250 1825);
PAINT MONO (-2250 1825);
DISPLAY INVISIBLE (-2250 1825);
FORCEADD OFFPAGE..2
(-2250 1975);
FORCEPROP 2 LAST $XR0 139 
J 0
(-2061 1975);
DISPLAY 0.638298 (-2061 1975);
PAINT MONO (-2061 1975);
FORCEPROP 2 LAST PATH I81
J 0
(-2050 2025);
DISPLAY 1.021277 (-2050 2025);
PAINT ORANGE (-2050 2025);
DISPLAY INVISIBLE (-2050 2025);
FORCEPROP 1 LAST COMMENT_BODY TRUE
J 0
(-2295 1880);
DISPLAY 1.404255 (-2295 1880);
PAINT PEACH (-2295 1880);
DISPLAY INVISIBLE (-2295 1880);
FORCEPROP 1 LAST OFFPAGE TRUE
J 0
(-1925 1850);
PAINT GREEN (-1925 1850);
DISPLAY INVISIBLE (-1925 1850);
FORCEPROP 2 LAST CDS_LIB mstr_standard
J 0
(-2250 1975);
PAINT ORANGE (-2250 1975);
DISPLAY INVISIBLE (-2250 1975);
FORCEADD OFFPAGE..2
(-2250 2575);
FORCEPROP 2 LAST $XR0 190 
J 0
(-2061 2575);
DISPLAY 0.638298 (-2061 2575);
PAINT MONO (-2061 2575);
FORCEPROP 2 LASTPIN (-2300 2575) SIG_NAME CLK_25M_CPLD
J 0
(-2925 2585);
DISPLAY 0.617021 (-2925 2585);
PAINT ORANGE (-2925 2585);
FORCEPROP 2 LAST PATH I87
J 0
(-2075 2650);
DISPLAY 1.021277 (-2075 2650);
PAINT ORANGE (-2075 2650);
DISPLAY INVISIBLE (-2075 2650);
FORCEPROP 1 LAST COMMENT_BODY TRUE
J 0
(-2295 2480);
DISPLAY 1.404255 (-2295 2480);
PAINT PEACH (-2295 2480);
DISPLAY INVISIBLE (-2295 2480);
FORCEPROP 1 LAST OFFPAGE TRUE
J 0
(-1925 2450);
PAINT GREEN (-1925 2450);
DISPLAY INVISIBLE (-1925 2450);
FORCEPROP 2 LAST CDS_LIB mstr_standard
J 0
(-2250 2575);
PAINT ORANGE (-2250 2575);
DISPLAY INVISIBLE (-2250 2575);
FORCEADD CAP_A..1
(-2975 3925);
FORCEPROP 1 LASTPIN (-2975 3825) $PN 2
J 0
(-2965 3805);
DISPLAY 0.617021 (-2965 3805);
PAINT WHITE (-2965 3805);
FORCEPROP 1 LASTPIN (-2975 4025) $PN 1
J 0
(-2965 4005);
DISPLAY 0.617021 (-2965 4005);
PAINT WHITE (-2965 4005);
FORCEPROP 1 LAST MATERIAL X6S
J 0
(-2925 3825);
DISPLAY 0.617021 (-2925 3825);
PAINT SKYBLUE (-2925 3825);
FORCEPROP 1 LAST VOLTAGE 6.3V
J 0
(-2925 3925);
DISPLAY 0.617021 (-2925 3925);
PAINT SKYBLUE (-2925 3925);
FORCEPROP 1 LAST PACK_TYPE 0402V
J 0
(-2925 3725);
DISPLAY 0.617021 (-2925 3725);
PAINT SKYBLUE (-2925 3725);
FORCEPROP 1 LAST TOLERANCE 10%
J 0
(-2925 3875);
DISPLAY 0.617021 (-2925 3875);
PAINT SKYBLUE (-2925 3875);
FORCEPROP 1 LAST VALUE 1.0UF
J 0
(-2925 3975);
DISPLAY 0.617021 (-2925 3975);
PAINT SKYBLUE (-2925 3975);
FORCEPROP 1 LAST PART_NUMBER D97712-004
J 0
(-2925 3775);
DISPLAY 0.617021 (-2925 3775);
PAINT BLUE (-2925 3775);
FORCEPROP 1 LAST LOCATION C2T31
J 0
(-2925 4025);
DISPLAY 0.617021 (-2925 4025);
PAINT AQUA (-2925 4025);
FORCEPROP 2 LAST ROOM SYS_CLOCK
J 0
(-2925 4075);
DISPLAY 1.127660 (-2925 4075);
PAINT WHITE (-2925 4075);
DISPLAY INVISIBLE (-2925 4075);
FORCEPROP 1 LAST PATH I89
J 0
(-2925 4075);
DISPLAY 0.978723 (-2925 4075);
PAINT WHITE (-2925 4075);
DISPLAY INVISIBLE (-2925 4075);
FORCEPROP 2 LAST $SEC 1
J 0
(-2925 4125);
DISPLAY 1.510638 (-2925 4125);
PAINT MONO (-2925 4125);
DISPLAY INVISIBLE (-2925 4125);
FORCEPROP 2 LAST CDS_SEC 1
J 0
(-2925 4125);
DISPLAY 2.276596 (-2925 4125);
PAINT ORANGE (-2925 4125);
DISPLAY INVISIBLE (-2925 4125);
FORCEPROP 2 LAST CDS_LIB dev_discrete
J 0
(-2975 3925);
PAINT ORANGE (-2975 3925);
DISPLAY INVISIBLE (-2975 3925);
FORCEPROP 2 LAST BOM_COST SM_CONTROLLER
J 0
(-2925 4050);
DISPLAY 1.617021 (-2925 4050);
PAINT WHITE (-2925 4050);
DISPLAY INVISIBLE (-2925 4050);
FORCEPROP 2 LAST CDS_LOCATION C2T31
J 0
(-2925 4025);
DISPLAY 0.617021 (-2925 4025);
PAINT AQUA (-2925 4025);
DISPLAY INVISIBLE (-2925 4025);
FORCEADD CAP_A..1
(-3400 3925);
FORCEPROP 1 LASTPIN (-3400 3825) $PN 2
J 0
(-3390 3805);
DISPLAY 0.617021 (-3390 3805);
PAINT WHITE (-3390 3805);
FORCEPROP 1 LASTPIN (-3400 4025) $PN 1
J 0
(-3390 4005);
DISPLAY 0.617021 (-3390 4005);
PAINT WHITE (-3390 4005);
FORCEPROP 1 LAST MATERIAL X7R
J 0
(-3350 3825);
DISPLAY 0.617021 (-3350 3825);
PAINT SKYBLUE (-3350 3825);
FORCEPROP 1 LAST VOLTAGE 25V
J 0
(-3350 3925);
DISPLAY 0.617021 (-3350 3925);
PAINT SKYBLUE (-3350 3925);
FORCEPROP 1 LAST PACK_TYPE 0402V
J 0
(-3350 3725);
DISPLAY 0.617021 (-3350 3725);
PAINT SKYBLUE (-3350 3725);
FORCEPROP 1 LAST TOLERANCE 10%
J 0
(-3350 3875);
DISPLAY 0.617021 (-3350 3875);
PAINT SKYBLUE (-3350 3875);
FORCEPROP 1 LAST VALUE 0.01UF
J 0
(-3350 3975);
DISPLAY 0.617021 (-3350 3975);
PAINT SKYBLUE (-3350 3975);
FORCEPROP 1 LAST PART_NUMBER A36096-045
J 0
(-3350 3775);
DISPLAY 0.617021 (-3350 3775);
PAINT BLUE (-3350 3775);
FORCEPROP 1 LAST LOCATION C2T27
J 0
(-3350 4025);
DISPLAY 0.617021 (-3350 4025);
PAINT AQUA (-3350 4025);
FORCEPROP 2 LAST ROOM SYS_CLOCK
J 0
(-3350 4075);
DISPLAY 1.127660 (-3350 4075);
PAINT WHITE (-3350 4075);
DISPLAY INVISIBLE (-3350 4075);
FORCEPROP 1 LAST PATH I90
J 0
(-3350 4075);
DISPLAY 0.978723 (-3350 4075);
PAINT WHITE (-3350 4075);
DISPLAY INVISIBLE (-3350 4075);
FORCEPROP 2 LAST $SEC 1
J 0
(-3350 4125);
DISPLAY 1.510638 (-3350 4125);
PAINT MONO (-3350 4125);
DISPLAY INVISIBLE (-3350 4125);
FORCEPROP 2 LAST CDS_SEC 1
J 0
(-3350 4125);
DISPLAY 2.276596 (-3350 4125);
PAINT ORANGE (-3350 4125);
DISPLAY INVISIBLE (-3350 4125);
FORCEPROP 2 LAST CDS_LIB dev_discrete
J 0
(-3400 3925);
PAINT ORANGE (-3400 3925);
DISPLAY INVISIBLE (-3400 3925);
FORCEPROP 2 LAST BOM_COST SM_CONTROLLER
J 0
(-3350 4050);
DISPLAY 1.617021 (-3350 4050);
PAINT WHITE (-3350 4050);
DISPLAY INVISIBLE (-3350 4050);
FORCEPROP 2 LAST CDS_LOCATION C2T27
J 0
(-3350 4025);
DISPLAY 0.617021 (-3350 4025);
PAINT AQUA (-3350 4025);
DISPLAY INVISIBLE (-3350 4025);
FORCEADD RES..1
(-3675 4150);
FORCEPROP 1 LASTPIN (-3775 4150) $PN 1
J 0
(-3763 4162);
DISPLAY 0.617021 (-3763 4162);
PAINT WHITE (-3763 4162);
FORCEPROP 1 LASTPIN (-3575 4150) $PN 2
J 0
(-3613 4162);
DISPLAY 0.617021 (-3613 4162);
PAINT WHITE (-3613 4162);
FORCEPROP 1 LAST WATTAGE 1/10W
J 2
(-3700 4000);
DISPLAY 0.617021 (-3700 4000);
PAINT SKYBLUE (-3700 4000);
FORCEPROP 1 LAST MATERIAL CHIP
J 0
(-3675 4000);
DISPLAY 0.617021 (-3675 4000);
PAINT SKYBLUE (-3675 4000);
FORCEPROP 1 LAST PACK_TYPE 0603
J 0
(-3775 3950);
DISPLAY 0.617021 (-3775 3950);
PAINT SKYBLUE (-3775 3950);
FORCEPROP 1 LAST TOLERANCE 1.0%
J 0
(-3675 4050);
DISPLAY 0.617021 (-3675 4050);
PAINT SKYBLUE (-3675 4050);
FORCEPROP 1 LAST VALUE 2.2
J 2
(-3700 4050);
DISPLAY 0.617021 (-3700 4050);
PAINT SKYBLUE (-3700 4050);
FORCEPROP 1 LAST PART_NUMBER G22026-127
J 0
(-3800 4100);
DISPLAY 0.617021 (-3800 4100);
PAINT BLUE (-3800 4100);
FORCEPROP 1 LAST LOCATION R2T23
J 0
(-3725 4200);
DISPLAY 0.617021 (-3725 4200);
PAINT AQUA (-3725 4200);
FORCEPROP 2 LAST ROOM SYS_CLOCK
J 0
(-3725 4300);
DISPLAY 1.127660 (-3725 4300);
PAINT WHITE (-3725 4300);
DISPLAY INVISIBLE (-3725 4300);
FORCEPROP 1 LAST PATH I94
J 0
(-3725 4300);
DISPLAY 0.978723 (-3725 4300);
PAINT WHITE (-3725 4300);
DISPLAY INVISIBLE (-3725 4300);
FORCEPROP 2 LAST CDS_LOCATION R2T23
J 0
(-3725 4200);
DISPLAY 0.617021 (-3725 4200);
PAINT AQUA (-3725 4200);
DISPLAY INVISIBLE (-3725 4200);
FORCEPROP 2 LAST $SEC 1
J 0
(-3725 4350);
DISPLAY 1.510638 (-3725 4350);
PAINT MONO (-3725 4350);
DISPLAY INVISIBLE (-3725 4350);
FORCEPROP 2 LAST CDS_SEC 1
J 0
(-3725 4350);
DISPLAY 2.276596 (-3725 4350);
PAINT ORANGE (-3725 4350);
DISPLAY INVISIBLE (-3725 4350);
FORCEPROP 2 LAST BOM_COST SM_CONTROLLER
J 0
(-3725 4225);
DISPLAY 1.617021 (-3725 4225);
PAINT WHITE (-3725 4225);
DISPLAY INVISIBLE (-3725 4225);
FORCEPROP 2 LAST CDS_LIB mstr_discrete
J 0
(-3675 4150);
DISPLAY 1.617021 (-3675 4150);
PAINT MONO (-3675 4150);
DISPLAY INVISIBLE (-3675 4150);
FORCEADD RES..1
(-2250 4200);
FORCEPROP 1 LASTPIN (-2350 4200) $PN 1
J 0
(-2338 4212);
DISPLAY 0.617021 (-2338 4212);
PAINT WHITE (-2338 4212);
FORCEPROP 1 LASTPIN (-2150 4200) $PN 2
J 0
(-2188 4212);
DISPLAY 0.617021 (-2188 4212);
PAINT WHITE (-2188 4212);
FORCEPROP 1 LAST WATTAGE 1/10W
J 2
(-2275 4050);
DISPLAY 0.617021 (-2275 4050);
PAINT SKYBLUE (-2275 4050);
FORCEPROP 1 LAST MATERIAL CHIP
J 0
(-2250 4050);
DISPLAY 0.617021 (-2250 4050);
PAINT SKYBLUE (-2250 4050);
FORCEPROP 1 LAST PACK_TYPE 0603
J 0
(-2350 4000);
DISPLAY 0.617021 (-2350 4000);
PAINT SKYBLUE (-2350 4000);
FORCEPROP 1 LAST TOLERANCE 1.0%
J 0
(-2250 4100);
DISPLAY 0.617021 (-2250 4100);
PAINT SKYBLUE (-2250 4100);
FORCEPROP 1 LAST VALUE 2.2
J 2
(-2275 4100);
DISPLAY 0.617021 (-2275 4100);
PAINT SKYBLUE (-2275 4100);
FORCEPROP 1 LAST PART_NUMBER G22026-127
J 0
(-2375 4150);
DISPLAY 0.617021 (-2375 4150);
PAINT BLUE (-2375 4150);
FORCEPROP 1 LAST LOCATION R2T52
J 0
(-2300 4250);
DISPLAY 0.617021 (-2300 4250);
PAINT AQUA (-2300 4250);
FORCEPROP 2 LAST ROOM SYS_CLOCK
J 0
(-2300 4350);
DISPLAY 1.127660 (-2300 4350);
PAINT WHITE (-2300 4350);
DISPLAY INVISIBLE (-2300 4350);
FORCEPROP 1 LAST PATH I95
J 0
(-2300 4350);
DISPLAY 0.978723 (-2300 4350);
PAINT WHITE (-2300 4350);
DISPLAY INVISIBLE (-2300 4350);
FORCEPROP 2 LAST CDS_LOCATION R2T52
J 0
(-2300 4250);
DISPLAY 0.617021 (-2300 4250);
PAINT AQUA (-2300 4250);
DISPLAY INVISIBLE (-2300 4250);
FORCEPROP 2 LAST $SEC 1
J 0
(-2300 4450);
DISPLAY 1.510638 (-2300 4450);
PAINT MONO (-2300 4450);
DISPLAY INVISIBLE (-2300 4450);
FORCEPROP 2 LAST CDS_SEC 1
J 0
(-2300 4400);
DISPLAY 2.276596 (-2300 4400);
PAINT ORANGE (-2300 4400);
DISPLAY INVISIBLE (-2300 4400);
FORCEPROP 2 LAST CDS_LIB mstr_discrete
J 0
(-2250 4200);
DISPLAY 2.127660 (-2250 4200);
PAINT ORANGE (-2250 4200);
DISPLAY INVISIBLE (-2250 4200);
FORCEPROP 2 LAST BOM_COST SM_CONTROLLER
J 0
(-2300 4275);
DISPLAY 1.617021 (-2300 4275);
PAINT WHITE (-2300 4275);
DISPLAY INVISIBLE (-2300 4275);
FORCEADD GND..1
(-2975 3625);
FORCEPROP 3 LASTPIN (-2975 3675) SIG_NAME GND\g
J 0
(-2965 3685);
DISPLAY 0.659574 (-2965 3685);
PAINT MONO (-2965 3685);
DISPLAY INVISIBLE (-2965 3685);
FORCEPROP 1 LAST HDL_POWER GND
J 0
(-2975 3775);
PAINT GREEN (-2975 3775);
DISPLAY INVISIBLE (-2975 3775);
FORCEPROP 2 LAST ROOM SYS_CLOCK
J 0
(-3300 3700);
DISPLAY 1.127660 (-3300 3700);
PAINT WHITE (-3300 3700);
DISPLAY INVISIBLE (-3300 3700);
FORCEPROP 1 LAST PATH I96
J 0
(-2900 3625);
DISPLAY 0.872340 (-2900 3625);
PAINT AQUA (-2900 3625);
DISPLAY INVISIBLE (-2900 3625);
FORCEPROP 1 LAST BODY_TYPE PLUMBING
J 0
(-3020 3582);
DISPLAY 0.340426 (-3020 3582);
PAINT GREEN (-3020 3582);
DISPLAY INVISIBLE (-3020 3582);
FORCEPROP 2 LAST BOM_COST SM_CONTROLLER
J 0
(-3425 3700);
DISPLAY 1.617021 (-3425 3700);
PAINT WHITE (-3425 3700);
DISPLAY INVISIBLE (-3425 3700);
FORCEPROP 2 LAST CDS_LIB mstr_symbols
J 0
(-2975 3625);
DISPLAY 1.617021 (-2975 3625);
PAINT MONO (-2975 3625);
DISPLAY INVISIBLE (-2975 3625);
FORCEPROP 1 LAST SIZE 1B
J 0
(-2900 3575);
DISPLAY 1.127660 (-2900 3575);
PAINT GREEN (-2900 3575);
DISPLAY INVISIBLE (-2900 3575);
FORCEPROP 1 LAST VOLTAGE 0.0V
J 0
(-3020 3582);
DISPLAY 0.340426 (-3020 3582);
PAINT SKYBLUE (-3020 3582);
DISPLAY INVISIBLE (-3020 3582);
FORCEADD CAP_A..1
(-1675 4000);
FORCEPROP 1 LASTPIN (-1675 3900) $PN 2
J 0
(-1665 3880);
DISPLAY 0.617021 (-1665 3880);
PAINT WHITE (-1665 3880);
FORCEPROP 1 LASTPIN (-1675 4100) $PN 1
J 0
(-1665 4080);
DISPLAY 0.617021 (-1665 4080);
PAINT WHITE (-1665 4080);
FORCEPROP 1 LAST MATERIAL X6S
J 0
(-1625 3900);
DISPLAY 0.617021 (-1625 3900);
PAINT SKYBLUE (-1625 3900);
FORCEPROP 1 LAST VOLTAGE 6.3V
J 0
(-1625 4000);
DISPLAY 0.617021 (-1625 4000);
PAINT SKYBLUE (-1625 4000);
FORCEPROP 1 LAST PACK_TYPE 0402V
J 0
(-1625 3800);
DISPLAY 0.617021 (-1625 3800);
PAINT SKYBLUE (-1625 3800);
FORCEPROP 1 LAST TOLERANCE 10%
J 0
(-1625 3950);
DISPLAY 0.617021 (-1625 3950);
PAINT SKYBLUE (-1625 3950);
FORCEPROP 1 LAST VALUE 1.0UF
J 0
(-1625 4050);
DISPLAY 0.617021 (-1625 4050);
PAINT SKYBLUE (-1625 4050);
FORCEPROP 1 LAST PART_NUMBER D97712-004
J 0
(-1625 3850);
DISPLAY 0.617021 (-1625 3850);
PAINT BLUE (-1625 3850);
FORCEPROP 1 LAST LOCATION C2T38
J 0
(-1625 4100);
DISPLAY 0.617021 (-1625 4100);
PAINT AQUA (-1625 4100);
FORCEPROP 2 LAST ROOM SYS_CLOCK
J 0
(-1625 4150);
DISPLAY 1.127660 (-1625 4150);
PAINT WHITE (-1625 4150);
DISPLAY INVISIBLE (-1625 4150);
FORCEPROP 1 LAST PATH I97
J 0
(-1625 4150);
DISPLAY 0.978723 (-1625 4150);
PAINT WHITE (-1625 4150);
DISPLAY INVISIBLE (-1625 4150);
FORCEPROP 2 LAST $SEC 1
J 0
(-1625 4200);
DISPLAY 1.510638 (-1625 4200);
PAINT MONO (-1625 4200);
DISPLAY INVISIBLE (-1625 4200);
FORCEPROP 2 LAST CDS_SEC 1
J 0
(-1625 4200);
DISPLAY 2.276596 (-1625 4200);
PAINT ORANGE (-1625 4200);
DISPLAY INVISIBLE (-1625 4200);
FORCEPROP 2 LAST CDS_LIB dev_discrete
J 0
(-1675 4000);
PAINT ORANGE (-1675 4000);
DISPLAY INVISIBLE (-1675 4000);
FORCEPROP 2 LAST BOM_COST SM_CONTROLLER
J 0
(-1625 4125);
DISPLAY 1.617021 (-1625 4125);
PAINT WHITE (-1625 4125);
DISPLAY INVISIBLE (-1625 4125);
FORCEPROP 2 LAST CDS_LOCATION C2T38
J 0
(-1625 4100);
DISPLAY 0.617021 (-1625 4100);
PAINT AQUA (-1625 4100);
DISPLAY INVISIBLE (-1625 4100);
FORCEADD GND..1
(-1675 3650);
FORCEPROP 3 LASTPIN (-1675 3700) SIG_NAME GND\g
J 0
(-1665 3710);
DISPLAY 0.659574 (-1665 3710);
PAINT MONO (-1665 3710);
DISPLAY INVISIBLE (-1665 3710);
FORCEPROP 1 LAST HDL_POWER GND
J 0
(-1675 3800);
PAINT GREEN (-1675 3800);
DISPLAY INVISIBLE (-1675 3800);
FORCEPROP 2 LAST ROOM SYS_CLOCK
J 0
(-2000 3725);
DISPLAY 1.127660 (-2000 3725);
PAINT WHITE (-2000 3725);
DISPLAY INVISIBLE (-2000 3725);
FORCEPROP 1 LAST PATH I98
J 0
(-1600 3650);
DISPLAY 0.872340 (-1600 3650);
PAINT AQUA (-1600 3650);
DISPLAY INVISIBLE (-1600 3650);
FORCEPROP 1 LAST BODY_TYPE PLUMBING
J 0
(-1720 3607);
DISPLAY 0.340426 (-1720 3607);
PAINT GREEN (-1720 3607);
DISPLAY INVISIBLE (-1720 3607);
FORCEPROP 2 LAST BOM_COST SM_CONTROLLER
J 0
(-2125 3725);
DISPLAY 1.617021 (-2125 3725);
PAINT WHITE (-2125 3725);
DISPLAY INVISIBLE (-2125 3725);
FORCEPROP 1 LAST SIZE 1B
J 0
(-1600 3600);
DISPLAY 1.127660 (-1600 3600);
PAINT GREEN (-1600 3600);
DISPLAY INVISIBLE (-1600 3600);
FORCEPROP 2 LAST CDS_LIB mstr_symbols
J 0
(-1675 3650);
DISPLAY 2.127660 (-1675 3650);
PAINT ORANGE (-1675 3650);
DISPLAY INVISIBLE (-1675 3650);
FORCEPROP 1 LAST VOLTAGE 0.0V
J 0
(-1720 3607);
DISPLAY 0.340426 (-1720 3607);
PAINT SKYBLUE (-1720 3607);
DISPLAY INVISIBLE (-1720 3607);
FORCEADD CAP_A..1
(-2050 4000);
FORCEPROP 1 LASTPIN (-2050 3900) $PN 2
J 0
(-2040 3880);
DISPLAY 0.617021 (-2040 3880);
PAINT WHITE (-2040 3880);
FORCEPROP 1 LASTPIN (-2050 4100) $PN 1
J 0
(-2040 4080);
DISPLAY 0.617021 (-2040 4080);
PAINT WHITE (-2040 4080);
FORCEPROP 1 LAST MATERIAL X7R
J 0
(-2000 3900);
DISPLAY 0.617021 (-2000 3900);
PAINT SKYBLUE (-2000 3900);
FORCEPROP 1 LAST VOLTAGE 25V
J 0
(-2000 4000);
DISPLAY 0.617021 (-2000 4000);
PAINT SKYBLUE (-2000 4000);
FORCEPROP 1 LAST PACK_TYPE 0402V
J 0
(-2000 3800);
DISPLAY 0.617021 (-2000 3800);
PAINT SKYBLUE (-2000 3800);
FORCEPROP 1 LAST TOLERANCE 10%
J 0
(-2000 3950);
DISPLAY 0.617021 (-2000 3950);
PAINT SKYBLUE (-2000 3950);
FORCEPROP 1 LAST VALUE 0.01UF
J 0
(-2000 4050);
DISPLAY 0.617021 (-2000 4050);
PAINT SKYBLUE (-2000 4050);
FORCEPROP 1 LAST PART_NUMBER A36096-045
J 0
(-2000 3850);
DISPLAY 0.617021 (-2000 3850);
PAINT BLUE (-2000 3850);
FORCEPROP 1 LAST LOCATION C2T37
J 0
(-2000 4100);
DISPLAY 0.617021 (-2000 4100);
PAINT AQUA (-2000 4100);
FORCEPROP 2 LAST ROOM SYS_CLOCK
J 0
(-2000 4150);
DISPLAY 1.127660 (-2000 4150);
PAINT WHITE (-2000 4150);
DISPLAY INVISIBLE (-2000 4150);
FORCEPROP 1 LAST PATH I99
J 0
(-2000 4150);
DISPLAY 0.978723 (-2000 4150);
PAINT WHITE (-2000 4150);
DISPLAY INVISIBLE (-2000 4150);
FORCEPROP 2 LAST $SEC 1
J 0
(-2000 4200);
DISPLAY 1.510638 (-2000 4200);
PAINT MONO (-2000 4200);
DISPLAY INVISIBLE (-2000 4200);
FORCEPROP 2 LAST CDS_SEC 1
J 0
(-2000 4200);
DISPLAY 2.276596 (-2000 4200);
PAINT ORANGE (-2000 4200);
DISPLAY INVISIBLE (-2000 4200);
FORCEPROP 2 LAST CDS_LIB dev_discrete
J 0
(-2050 4000);
PAINT ORANGE (-2050 4000);
DISPLAY INVISIBLE (-2050 4000);
FORCEPROP 2 LAST BOM_COST SM_CONTROLLER
J 0
(-2000 4125);
DISPLAY 1.617021 (-2000 4125);
PAINT WHITE (-2000 4125);
DISPLAY INVISIBLE (-2000 4125);
FORCEPROP 2 LAST CDS_LOCATION C2T37
J 0
(-2000 4100);
DISPLAY 0.617021 (-2000 4100);
PAINT AQUA (-2000 4100);
DISPLAY INVISIBLE (-2000 4100);
FORCEADD CAD_NOTE..1
(-8325 3400);
FORCEPROP 0 LAST L4 CURRENT SHOULD FLOW THROUGH 10UF CAP PAD
J 0
(-8475 3125);
DISPLAY 0.744681 (-8475 3125);
PAINT WHITE (-8475 3125);
FORCEPROP 0 LAST L3 PLACE ALL 0.1UF NEAR CHIP PIN
J 0
(-8475 3175);
DISPLAY 0.744681 (-8475 3175);
PAINT WHITE (-8475 3175);
FORCEPROP 0 LAST L2 PLACE 10UF CAP CLOSE TO FERRITE BEAD
J 0
(-8475 3225);
DISPLAY 0.744681 (-8475 3225);
PAINT WHITE (-8475 3225);
FORCEPROP 0 LAST L1 10UF CAP AND 0.1UF CAP SHOULD BE SEPARATED BY 250MILS
J 0
(-8475 3275);
DISPLAY 0.744681 (-8475 3275);
PAINT WHITE (-8475 3275);
FORCEPROP 1 LAST COMMENT_BODY TRUE
J 0
(-8300 3500);
DISPLAY 2.212766 (-8300 3500);
PAINT PEACH (-8300 3500);
DISPLAY INVISIBLE (-8300 3500);
FORCEPROP 2 LAST CDS_LIB mstr_symbols
J 0
(-8325 3400);
DISPLAY 1.617021 (-8325 3400);
PAINT WHITE (-8325 3400);
DISPLAY INVISIBLE (-8325 3400);
FORCEADD CAD_NOTE..1
(-3625 3525);
FORCEPROP 0 LAST L1 PLACE 0.01UF NEAR CHIP PIN
J 0
(-3775 3400);
DISPLAY 1.170213 (-3775 3400);
PAINT WHITE (-3775 3400);
FORCEPROP 1 LAST COMMENT_BODY TRUE
J 0
(-3600 3625);
DISPLAY 2.212766 (-3600 3625);
PAINT PEACH (-3600 3625);
DISPLAY INVISIBLE (-3600 3625);
FORCEPROP 2 LAST CDS_LIB mstr_symbols
J 0
(-3625 3525);
DISPLAY 1.617021 (-3625 3525);
PAINT WHITE (-3625 3525);
DISPLAY INVISIBLE (-3625 3525);
FORCEADD INTEL_CORP_BPAGE..1
(-1025 -350);
FORCEPROP 1 LAST CDS_CON_LAST_MODIFIED Tue Dec 01 11:51:50 2015
J 0
(-2450 -25);
DISPLAY 0.489362 (-2450 -25);
PAINT GREEN (-2450 -25);
DISPLAY INVISIBLE (-2450 -25);
FORCEPROP 1 LAST CUSTOM_TXT_CDS <CURRENT_DESIGN_SHEET> OF <TOTAL_DESIGN_SHEETS>
J 0
(-1525 -325);
PAINT GREEN (-1525 -325);
FORCEPROP 1 LAST CUSTOM_TXT_CDS <CON_LAST_MODIFIED>
J 0
(-2950 0);
PAINT GREEN (-2950 0);
FORCEPROP 2 LAST CUSTOM_TXT_CDS <XR_PAGE_TITLE>
J 0
(-8915 4900);
DISPLAY 0.638298 (-8915 4900);
PAINT PINK (-8915 4900);
DISPLAY INVISIBLE (-8915 4900);
FORCEPROP 1 LAST SCH_TITLE CKMNG+
J 0
(-8925 -250);
DISPLAY 1.212766 (-8925 -250);
PAINT GREEN (-8925 -250);
FORCEPROP 1 LAST SCH_ADDRESS1 2200 Mission College Blvd.
J 0
(-5000 -225);
DISPLAY 0.617021 (-5000 -225);
PAINT GREEN (-5000 -225);
FORCEPROP 1 LAST SCH_ADDRESS2 P.O. BOX 58119
J 0
(-5000 -275);
DISPLAY 0.617021 (-5000 -275);
PAINT GREEN (-5000 -275);
FORCEPROP 1 LAST SCH_ADDRESS3 Santa Clara, CA 95052-8119
J 0
(-5000 -325);
DISPLAY 0.617021 (-5000 -325);
PAINT GREEN (-5000 -325);
FORCEPROP 1 LAST SCH_REV 2.420
J 0
(-1275 -200);
DISPLAY 0.978723 (-1275 -200);
PAINT YELLOW (-1275 -200);
FORCEPROP 1 LAST SCH_DEPT BESD
J 1
(-5475 -250);
DISPLAY 1.212766 (-5475 -250);
PAINT YELLOW (-5475 -250);
FORCEPROP 1 LAST SCH_NUMBER H4694802
J 0
(-2325 -200);
DISPLAY 1.212766 (-2325 -200);
PAINT YELLOW (-2325 -200);
FORCEPROP 1 LAST COMMENT_BODY TRUE
J 0
(-1013 -338);
DISPLAY 0.234043 (-1013 -338);
PAINT GREEN (-1013 -338);
DISPLAY INVISIBLE (-1013 -338);
FORCEPROP 2 LAST CDS_LIB mstr_symbols
J 0
(-1025 -350);
DISPLAY 0.489362 (-1025 -350);
PAINT ORANGE (-1025 -350);
DISPLAY INVISIBLE (-1025 -350);
FORCEPROP 2 LAST PAGE_BORDER TRUE
J 0
(-8915 4900);
DISPLAY 0.425532 (-8915 4900);
PAINT PINK (-8915 4900);
DISPLAY INVISIBLE (-8915 4900);
FORCEPROP 2 LAST CDS_XR_PAGE_TITLE CR-101 : @BASEBOARD_FAB2_LIB.BASEBOARD_FAB2(SCH_1):PAGE101
J 0
(-8915 4900);
DISPLAY 0.638298 (-8915 4900);
PAINT PINK (-8915 4900);
DISPLAY INVISIBLE (-8915 4900);
FORCEADD CAD_NOTE..1
(-8275 475);
FORCEPROP 0 LAST L1 PLACE CAPS CLOSE TO CK-MNG+ PINS
J 0
(-8425 350);
DISPLAY 1.170213 (-8425 350);
PAINT WHITE (-8425 350);
FORCEPROP 1 LAST COMMENT_BODY TRUE
J 0
(-8250 575);
DISPLAY 2.212766 (-8250 575);
PAINT PEACH (-8250 575);
DISPLAY INVISIBLE (-8250 575);
FORCEPROP 2 LAST CDS_LIB mstr_symbols
J 0
(-8275 475);
DISPLAY 1.617021 (-8275 475);
PAINT WHITE (-8275 475);
DISPLAY INVISIBLE (-8275 475);
FORCEADD CAD_NOTE..1
(-4050 3050);
FORCEPROP 0 LAST L1 PLACE SOURCE TERM RES WITHIN 1 INCH OF CKMNG+
J 0
(-4200 2925);
DISPLAY 1.170213 (-4200 2925);
PAINT WHITE (-4200 2925);
FORCEPROP 1 LAST COMMENT_BODY TRUE
J 0
(-4025 3150);
DISPLAY 1.595745 (-4025 3150);
PAINT PEACH (-4025 3150);
DISPLAY INVISIBLE (-4025 3150);
FORCEPROP 2 LAST CDS_LIB mstr_symbols
J 0
(-4050 3050);
DISPLAY 1.617021 (-4050 3050);
PAINT MONO (-4050 3050);
DISPLAY INVISIBLE (-4050 3050);
WIRE 16 -1 (-3850 4150)(-3775 4150);
WIRE 16 -1 (-3850 4300)(-3850 4150);
WIRE 16 -1 (-3400 4025)(-3400 4150);
WIRE 16 -1 (-2975 4150)(-3400 4150);
WIRE 16 -1 (-3400 4150)(-3575 4150);
WIRE 16 -1 (-2975 4025)(-2975 4150);
WIRE 16 -1 (-2975 4150)(-2975 4225);
FORCEPROP 0 LAST VOLTAGE +3.3V
J 0
(-3150 4200);
DISPLAY 1.021277 (-3150 4200);
PAINT SKYBLUE (-3150 4200);
DISPLAY INVISIBLE (-3150 4200);
WIRE 16 -1 (-2350 4200)(-2425 4200);
WIRE 16 -1 (-2425 4200)(-2425 4325);
WIRE 16 -1 (-2050 4100)(-2050 4200);
WIRE 16 -1 (-2050 4200)(-1675 4200);
WIRE 16 -1 (-2150 4200)(-2050 4200);
WIRE 16 -1 (-1675 4100)(-1675 4200);
WIRE 16 -1 (-1675 4275)(-1675 4200);
FORCEPROP 0 LAST VOLTAGE +3.3V
J 0
(-1675 4300);
DISPLAY 1.021277 (-1675 4300);
PAINT SKYBLUE (-1675 4300);
DISPLAY INVISIBLE (-1675 4300);
WIRE 16 -1 (-4875 3900)(-4875 3775);
WIRE 16 -1 (-4475 3775)(-4875 3775);
WIRE 16 -1 (-4475 3775)(-4475 3900);
WIRE 16 -1 (-4475 3775)(-4475 3725);
WIRE 16 -1 (-7900 3725)(-7600 3725);
WIRE 16 -1 (-7900 3725)(-7900 3875);
WIRE 16 -1 (-7300 3725)(-7600 3725);
WIRE 16 -1 (-7600 3725)(-7600 3875);
WIRE 16 -1 (-6900 3725)(-7300 3725);
WIRE 16 -1 (-7300 3725)(-7300 3875);
WIRE 16 -1 (-6600 3725)(-6900 3725);
WIRE 16 -1 (-6900 3725)(-6900 3875);
WIRE 16 -1 (-6600 3875)(-6600 3725);
WIRE 16 -1 (-6600 3675)(-6600 3725);
WIRE 16 -1 (-8225 4125)(-8475 4125);
WIRE 16 -1 (-8475 4300)(-8475 4125);
WIRE 16 -1 (-8475 4125)(-8475 4050);
WIRE 16 -1 (-7600 4125)(-7900 4125);
WIRE 16 -1 (-7600 4075)(-7600 4125);
WIRE 16 -1 (-7300 4125)(-7600 4125);
WIRE 16 -1 (-8025 4125)(-7900 4125);
WIRE 16 -1 (-7900 4125)(-7900 4075);
WIRE 16 -1 (-6900 4125)(-7300 4125);
WIRE 16 -1 (-7300 4125)(-7300 4075);
WIRE 16 -1 (-6600 4125)(-6900 4125);
WIRE 16 -1 (-6900 4125)(-6900 4075);
WIRE 16 -1 (-6600 4075)(-6600 4125);
WIRE 16 -1 (-6600 4125)(-6600 4225);
WIRE 16 -1 (-5250 4175)(-5425 4175);
WIRE 16 -1 (-5425 4325)(-5425 4175);
WIRE 16 -1 (-6675 2525)(-6675 3150);
WIRE 16 -1 (-6675 2525)(-6525 2525);
WIRE 16 -1 (-6525 2375)(-6975 2375);
WIRE 16 -1 (-6975 2375)(-6975 2425);
WIRE 16 -1 (-6975 2425)(-6525 2425);
WIRE 16 -1 (-6975 2950)(-6975 2425);
WIRE 16 -1 (-4875 4100)(-4875 4175);
WIRE 16 -1 (-4475 4175)(-4875 4175);
WIRE 16 -1 (-5050 4175)(-4875 4175);
WIRE 16 -1 (-4475 4100)(-4475 4175);
WIRE 16 -1 (-4475 4175)(-4475 4275);
WIRE 16 -1 (-7375 2075)(-6525 2075);
WIRE 16 -1 (-7375 2125)(-7375 2075);
WIRE 16 -1 (-6525 2125)(-7375 2125);
WIRE 16 -1 (-7375 2225)(-7375 2125);
WIRE 16 -1 (-6525 2225)(-7375 2225);
WIRE 16 -1 (-7375 2275)(-7375 2225);
WIRE 16 -1 (-6525 2275)(-7375 2275);
FORCEPROP 0 LAST VOLTAGE +3.3V
J 0
(-7350 2350);
DISPLAY 1.021277 (-7350 2350);
PAINT SKYBLUE (-7350 2350);
DISPLAY INVISIBLE (-7350 2350);
WIRE 16 -1 (-7375 2275)(-7375 2450);
WIRE 16 -1 (-6525 2025)(-7875 2025);
FORCEPROP 0 LAST VOLTAGE +3.3V
J 0
(-7400 2100);
DISPLAY 1.021277 (-7400 2100);
PAINT SKYBLUE (-7400 2100);
DISPLAY INVISIBLE (-7400 2100);
WIRE 16 -1 (-7875 2325)(-7875 2025);
WIRE 16 -1 (-4750 2825)(-4750 2875);
WIRE 16 -1 (-5225 1525)(-5025 1525);
WIRE 16 -1 (-5025 1525)(-5025 1425);
WIRE 16 -1 (-5225 1425)(-5025 1425);
WIRE 16 -1 (-5025 1425)(-5025 1375);
WIRE 16 -1 (-5225 1375)(-5025 1375);
WIRE 16 -1 (-5025 1375)(-5025 1275);
WIRE 16 -1 (-5225 1275)(-5025 1275);
WIRE 16 -1 (-5025 1275)(-5025 1225);
WIRE 16 -1 (-5225 1225)(-5025 1225);
WIRE 16 -1 (-5025 1225)(-5025 1175);
WIRE 16 -1 (-5225 1175)(-5025 1175);
WIRE 16 -1 (-5025 1175)(-5025 1075);
WIRE 16 -1 (-5225 1075)(-5025 1075);
WIRE 16 -1 (-5025 1075)(-5025 1025);
WIRE 16 -1 (-5225 1025)(-5025 1025);
WIRE 16 -1 (-5025 1025)(-5025 975);
WIRE 16 -1 (-5225 975)(-5025 975);
WIRE 16 -1 (-5025 975)(-5025 825);
WIRE 16 -1 (-7625 575)(-7450 575);
WIRE 16 -1 (-7625 575)(-7625 675);
WIRE 16 -1 (-7275 575)(-7450 575);
WIRE 16 -1 (-7450 575)(-7450 525);
WIRE 16 -1 (-7275 675)(-7275 575);
WIRE 16 -1 (-8475 3850)(-8475 3700);
WIRE 16 -1 (-8300 1100)(-8300 925);
WIRE 16 -1 (-3400 3825)(-3400 3700);
WIRE 16 -1 (-2975 3700)(-3400 3700);
WIRE 16 -1 (-2975 3700)(-2975 3825);
WIRE 16 -1 (-2975 3700)(-2975 3675);
WIRE 16 -1 (-2050 3900)(-2050 3750);
WIRE 16 -1 (-2050 3750)(-1675 3750);
WIRE 16 -1 (-1675 3750)(-1675 3900);
WIRE 16 -1 (-1675 3750)(-1675 3700);
WIRE 16 -1 (-4075 2175)(-4075 1825);
WIRE 16 -1 (-5225 2175)(-4075 2175);
FORCEPROP 2 LAST SIG_NAME CLK_50M_CKMNG_BMC_2_R
J 0
(-5125 2185);
DISPLAY 0.617021 (-5125 2185);
PAINT ORANGE (-5125 2185);
FORCEPROP 2 LASTPROP $XRERR UNIQUE?
J 0
(-5365 2185);
DISPLAY 0.638298 (-5365 2185);
PAINT MONO (-5365 2185);
DISPLAY INVISIBLE (-5365 2185);
WIRE 16 -1 (-4075 1825)(-3525 1825);
WIRE 16 -1 (-5225 2275)(-3975 2275);
FORCEPROP 2 LAST SIG_NAME CLK_50M_CKMNG_PCH_10GBE_R
J 0
(-5125 2285);
DISPLAY 0.617021 (-5125 2285);
PAINT ORANGE (-5125 2285);
FORCEPROP 2 LASTPROP $XRERR UNIQUE?
J 0
(-5365 2285);
DISPLAY 0.638298 (-5365 2285);
PAINT MONO (-5365 2285);
DISPLAY INVISIBLE (-5365 2285);
WIRE 16 -1 (-3975 2275)(-3975 2125);
WIRE 16 -1 (-3975 2125)(-3525 2125);
WIRE 16 -1 (-4025 2225)(-4025 1975);
WIRE 16 -1 (-5225 2225)(-4025 2225);
FORCEPROP 2 LAST SIG_NAME CLK_50M_CKMNG_SPRVLLE_R
J 0
(-5125 2235);
DISPLAY 0.617021 (-5125 2235);
PAINT ORANGE (-5125 2235);
FORCEPROP 2 LASTPROP $XRERR UNIQUE?
J 0
(-5365 2235);
DISPLAY 0.638298 (-5365 2235);
PAINT MONO (-5365 2235);
DISPLAY INVISIBLE (-5365 2235);
WIRE 16 -1 (-4025 1975)(-3525 1975);
WIRE 16 -1 (-5225 2425)(-3525 2425);
FORCEPROP 2 LAST SIG_NAME CLK_25M_BMC_R
J 0
(-5125 2435);
DISPLAY 0.617021 (-5125 2435);
PAINT ORANGE (-5125 2435);
FORCEPROP 2 LASTPROP $XRERR UNIQUE?
J 0
(-5365 2435);
DISPLAY 0.638298 (-5365 2435);
PAINT MONO (-5365 2435);
DISPLAY INVISIBLE (-5365 2435);
WIRE 16 -1 (-6775 1425)(-6525 1425);
WIRE 16 -1 (-6775 1375)(-6775 1425);
WIRE 16 -1 (-6775 1425)(-8300 1425);
FORCEPROP 0 LAST SIG_NAME PD_CKMNG_OE
J 0
(-7835 1435);
DISPLAY 0.617021 (-7835 1435);
PAINT ORANGE (-7835 1435);
FORCEPROP 2 LASTPROP $XRERR UNIQUE?
J 0
(-8075 1435);
DISPLAY 0.638298 (-8075 1435);
PAINT MONO (-8075 1435);
DISPLAY INVISIBLE (-8075 1435);
WIRE 16 -1 (-8300 1425)(-8300 1300);
WIRE 16 -1 (-6525 1375)(-6775 1375);
WIRE 16 -1 (-7350 1000)(-7275 1000);
WIRE 16 -1 (-7275 1175)(-7275 1000);
WIRE 16 -1 (-7275 875)(-7275 1000);
WIRE 16 -1 (-7275 1175)(-6525 1175);
FORCEPROP 2 LAST SIG_NAME XTAL_CK_MNG_IN
J 0
(-7085 1185);
DISPLAY 0.617021 (-7085 1185);
PAINT ORANGE (-7085 1185);
FORCEPROP 2 LASTPROP $XRERR UNIQUE?
J 0
(-7325 1185);
DISPLAY 0.638298 (-7325 1185);
PAINT MONO (-7325 1185);
DISPLAY INVISIBLE (-7325 1185);
WIRE 16 -1 (-7625 875)(-7625 1000);
WIRE 16 -1 (-7625 1225)(-7625 1000);
WIRE 16 -1 (-7625 1000)(-7550 1000);
WIRE 16 -1 (-7625 1225)(-6525 1225);
FORCEPROP 2 LAST SIG_NAME XTAL_CK_MNG_OUT
J 0
(-7085 1235);
DISPLAY 0.617021 (-7085 1235);
PAINT ORANGE (-7085 1235);
FORCEPROP 2 LASTPROP $XRERR UNIQUE?
J 0
(-7325 1235);
DISPLAY 0.638298 (-7325 1235);
PAINT MONO (-7325 1235);
DISPLAY INVISIBLE (-7325 1235);
WIRE 16 -1 (-6525 1575)(-7275 1575);
FORCEPROP 2 LAST SIG_NAME TP_33P_33M_SMBADR
J 0
(-7260 1585);
DISPLAY 0.617021 (-7260 1585);
PAINT ORANGE (-7260 1585);
FORCEPROP 2 LASTPROP $XRERR UNIQUE?
J 0
(-7515 1575);
DISPLAY 0.638298 (-7515 1575);
PAINT MONO (-7515 1575);
DISPLAY INVISIBLE (-7515 1575);
WIRE 16 -1 (-6650 1075)(-6525 1075);
WIRE 16 -1 (-6650 1075)(-6650 200);
WIRE 16 -1 (-6650 200)(-7750 200);
FORCEPROP 2 LAST SIG_NAME PWRGD_P3V3_STBY
J 0
(-7760 210);
DISPLAY 0.617021 (-7760 210);
PAINT ORANGE (-7760 210);
WIRE 16 -1 (-7150 1875)(-6525 1875);
FORCEPROP 2 LAST SIG_NAME SMB_HOST_STBY_LVC3_SDA
J 0
(-7160 1885);
DISPLAY 0.617021 (-7160 1885);
PAINT ORANGE (-7160 1885);
WIRE 16 -1 (-6525 1925)(-7150 1925);
FORCEPROP 2 LAST SIG_NAME SMB_HOST_STBY_LVC3_SCL
J 0
(-7160 1935);
DISPLAY 0.617021 (-7160 1935);
PAINT ORANGE (-7160 1935);
WIRE 16 3135 (-5300 675)(-5300 825);
WIRE 16 3135 (-6500 675)(-5300 675);
WIRE 16 3135 (-5300 825)(-6500 825);
WIRE 16 3135 (-6500 825)(-6500 675);
WIRE 16 -1 (-5225 1975)(-4375 1975);
FORCEPROP 2 LAST SIG_NAME TP_CLK_125M
J 0
(-5125 1985);
DISPLAY 0.617021 (-5125 1985);
PAINT ORANGE (-5125 1985);
FORCEPROP 2 LASTPROP $XRERR UNIQUE?
J 0
(-4345 1975);
DISPLAY 0.638298 (-4345 1975);
PAINT MONO (-4345 1975);
DISPLAY INVISIBLE (-4345 1975);
WIRE 16 -1 (-5225 1925)(-4375 1925);
FORCEPROP 2 LAST SIG_NAME TP_CLK_125M_BMCA
J 0
(-5125 1935);
DISPLAY 0.617021 (-5125 1935);
PAINT ORANGE (-5125 1935);
FORCEPROP 2 LASTPROP $XRERR UNIQUE?
J 0
(-4345 1925);
DISPLAY 0.638298 (-4345 1925);
PAINT MONO (-4345 1925);
DISPLAY INVISIBLE (-4345 1925);
WIRE 16 -1 (-5225 1825)(-4375 1825);
FORCEPROP 2 LAST SIG_NAME TP_CLK_96M_CKMNG_N
J 0
(-5125 1835);
DISPLAY 0.617021 (-5125 1835);
PAINT ORANGE (-5125 1835);
FORCEPROP 2 LASTPROP $XRERR UNIQUE?
J 0
(-4345 1825);
DISPLAY 0.638298 (-4345 1825);
PAINT MONO (-4345 1825);
DISPLAY INVISIBLE (-4345 1825);
WIRE 16 -1 (-5225 1775)(-4375 1775);
FORCEPROP 2 LAST SIG_NAME TP_CLK_96M_CKMNG_P
J 0
(-5125 1785);
DISPLAY 0.617021 (-5125 1785);
PAINT ORANGE (-5125 1785);
FORCEPROP 2 LASTPROP $XRERR UNIQUE?
J 0
(-4345 1775);
DISPLAY 0.638298 (-4345 1775);
PAINT MONO (-4345 1775);
DISPLAY INVISIBLE (-4345 1775);
WIRE 16 -1 (-5225 1675)(-4375 1675);
FORCEPROP 2 LAST SIG_NAME TP_CLK_100M_R_DN
J 0
(-5125 1685);
DISPLAY 0.617021 (-5125 1685);
PAINT ORANGE (-5125 1685);
FORCEPROP 2 LASTPROP $XRERR UNIQUE?
J 0
(-4345 1675);
DISPLAY 0.638298 (-4345 1675);
PAINT MONO (-4345 1675);
DISPLAY INVISIBLE (-4345 1675);
WIRE 16 -1 (-5225 1625)(-4375 1625);
FORCEPROP 2 LAST SIG_NAME TP_CLK_100M_R_DP
J 0
(-5125 1635);
DISPLAY 0.617021 (-5125 1635);
PAINT ORANGE (-5125 1635);
FORCEPROP 2 LASTPROP $XRERR UNIQUE?
J 0
(-4345 1625);
DISPLAY 0.638298 (-4345 1625);
PAINT MONO (-4345 1625);
DISPLAY INVISIBLE (-4345 1625);
WIRE 16 -1 (-4750 3075)(-4750 3150);
WIRE 16 -1 (-4750 3150)(-5150 3150);
FORCEPROP 2 LAST SIG_NAME A_COMP_CKMNG
J 0
(-5110 3175);
DISPLAY 0.617021 (-5110 3175);
PAINT ORANGE (-5110 3175);
FORCEPROP 2 LASTPROP $XRERR UNIQUE?
J 0
(-5350 3175);
DISPLAY 0.638298 (-5350 3175);
PAINT MONO (-5350 3175);
DISPLAY INVISIBLE (-5350 3175);
WIRE 16 -1 (-5150 3150)(-5150 2625);
WIRE 16 -1 (-5150 2625)(-5225 2625);
WIRE 16 -1 (-5225 2325)(-4375 2325);
FORCEPROP 2 LAST SIG_NAME TP_CLK5_50M_CKMNG
J 0
(-5125 2335);
DISPLAY 0.617021 (-5125 2335);
PAINT ORANGE (-5125 2335);
FORCEPROP 2 LASTPROP $XRERR UNIQUE?
J 0
(-4345 2325);
DISPLAY 0.638298 (-4345 2325);
PAINT MONO (-4345 2325);
DISPLAY INVISIBLE (-4345 2325);
WIRE 16 -1 (-5225 2125)(-4125 2125);
FORCEPROP 0 LAST SIG_NAME CLK_50M_CKMNG_BMC_1_R
J 0
(-5125 2135);
DISPLAY 0.617021 (-5125 2135);
PAINT ORANGE (-5125 2135);
FORCEPROP 2 LASTPROP $XRERR UNIQUE?
J 0
(-5365 2135);
DISPLAY 0.638298 (-5365 2135);
PAINT MONO (-5365 2135);
DISPLAY INVISIBLE (-5365 2135);
WIRE 16 -1 (-4125 2125)(-4125 1675);
WIRE 16 -1 (-4125 1675)(-3525 1675);
WIRE 16 -1 (-5225 2075)(-4175 2075);
FORCEPROP 0 LAST SIG_NAME CLK_50M_CKMNG_OCP_R
J 0
(-5125 2085);
DISPLAY 0.617021 (-5125 2085);
PAINT ORANGE (-5125 2085);
FORCEPROP 2 LASTPROP $XRERR UNIQUE?
J 0
(-5365 2085);
DISPLAY 0.638298 (-5365 2085);
PAINT MONO (-5365 2085);
DISPLAY INVISIBLE (-5365 2085);
WIRE 16 -1 (-4175 2075)(-4175 1525);
WIRE 16 -1 (-4175 1525)(-3525 1525);
WIRE 16 -1 (-5225 2575)(-4175 2575);
FORCEPROP 2 LAST SIG_NAME CLK_32K_SUSCLK_PLD_R
J 0
(-5125 2585);
DISPLAY 0.617021 (-5125 2585);
PAINT ORANGE (-5125 2585);
FORCEPROP 2 LASTPROP $XRERR UNIQUE?
J 0
(-5365 2585);
DISPLAY 0.638298 (-5365 2585);
PAINT MONO (-5365 2585);
DISPLAY INVISIBLE (-5365 2585);
WIRE 16 -1 (-4175 2575)(-4175 2750);
WIRE 16 -1 (-4175 2750)(-3525 2750);
WIRE 16 -1 (-5225 2475)(-4125 2475);
FORCEPROP 2 LAST SIG_NAME CLK_25M_CPLD_R
J 0
(-5125 2485);
DISPLAY 0.617021 (-5125 2485);
PAINT ORANGE (-5125 2485);
FORCEPROP 2 LASTPROP $XRERR UNIQUE?
J 0
(-5365 2485);
DISPLAY 0.638298 (-5365 2485);
PAINT MONO (-5365 2485);
DISPLAY INVISIBLE (-5365 2485);
WIRE 16 -1 (-4125 2475)(-4125 2575);
WIRE 16 -1 (-4125 2575)(-3525 2575);
WIRE 16 -1 (-3325 1675)(-2300 1675);
FORCEPROP 2 LAST SIG_NAME CLK_50M_CKMNG_BMC_1
J 0
(-2925 1685);
DISPLAY 0.617021 (-2925 1685);
PAINT ORANGE (-2925 1685);
WIRE 16 -1 (-3325 1525)(-2300 1525);
FORCEPROP 2 LAST SIG_NAME CLK_50M_CKMNG_OCP
J 0
(-2925 1535);
DISPLAY 0.617021 (-2925 1535);
PAINT ORANGE (-2925 1535);
WIRE 16 -1 (-3325 1825)(-2300 1825);
FORCEPROP 2 LAST SIG_NAME CLK_50M_CKMNG_BMC_2
J 0
(-2925 1835);
DISPLAY 0.617021 (-2925 1835);
PAINT ORANGE (-2925 1835);
WIRE 16 -1 (-3325 1975)(-2300 1975);
FORCEPROP 2 LAST SIG_NAME CLK_50M_CKMNG_SPRVLLE
J 0
(-2925 1985);
DISPLAY 0.617021 (-2925 1985);
PAINT ORANGE (-2925 1985);
WIRE 16 -1 (-3325 2750)(-2300 2750);
FORCEPROP 2 LAST SIG_NAME CLK_32K_SUSCLK_PLD
J 0
(-2925 2760);
DISPLAY 0.617021 (-2925 2760);
PAINT ORANGE (-2925 2760);
WIRE 16 -1 (-3325 2425)(-2300 2425);
FORCEPROP 2 LAST SIG_NAME CLK_25M_BMC
J 0
(-2925 2435);
DISPLAY 0.617021 (-2925 2435);
PAINT ORANGE (-2925 2435);
WIRE 16 -1 (-3325 2125)(-2300 2125);
FORCEPROP 2 LAST SIG_NAME CLK_50M_CKMNG_PCH_10GBE
J 0
(-2925 2135);
DISPLAY 0.617021 (-2925 2135);
PAINT ORANGE (-2925 2135);
WIRE 16 -1 (-2300 2575)(-3325 2575);
DOT 1 (-2050 4200);
DOT 1 (-1675 4200);
DOT 1 (-4875 4175);
DOT 1 (-4475 3775);
DOT 1 (-4475 4175);
DOT 1 (-6600 4125);
DOT 1 (-6900 4125);
DOT 1 (-7300 4125);
DOT 1 (-7600 4125);
DOT 1 (-7900 4125);
DOT 1 (-8475 4125);
DOT 1 (-3400 4150);
DOT 1 (-2975 3700);
DOT 1 (-1675 3750);
DOT 1 (-7600 3725);
DOT 1 (-7300 3725);
DOT 1 (-6900 3725);
DOT 1 (-6600 3725);
DOT 1 (-7375 2125);
DOT 1 (-7375 2275);
DOT 1 (-7375 2225);
DOT 1 (-6775 1425);
DOT 1 (-6975 2425);
DOT 1 (-5025 1025);
DOT 1 (-5025 1375);
DOT 1 (-5025 1425);
DOT 1 (-5025 975);
DOT 1 (-7275 1000);
DOT 1 (-7625 1000);
DOT 1 (-7450 575);
DOT 1 (-2975 4150);
DOT 1 (-5025 1175);
DOT 1 (-5025 1075);
DOT 1 (-5025 1275);
DOT 1 (-5025 1225);
FORCENOTE
ROOM=SYS_CLOCK
(-8966 -128) 0;
DISPLAY LEFT (-8966 -128);
PAINT PURPLE (-8966 -128);
FORCENOTE
SMBUS ADDRESS =0XD0
(-6450 725) 0;
DISPLAY LEFT (-6450 725);
DISPLAY 1.170213 (-6450 725);
PAINT PURPLE (-6450 725);
FORCENOTE
CKMNG+
(-6075 2900) 0;
DISPLAY LEFT (-6075 2900);
DISPLAY 1.595745 (-6075 2900);
PAINT PURPLE (-6075 2900);
QUIT
